FILE_TYPE = MACRO_DRAWING;
SET COLOR_WIRE YELLOW;
SET COLOR_PROP ORANGE;
SET COLOR_DOT WHITE;
SET COLOR_ARC YELLOW;
SET COLOR_BODY GREEN;
SET COLOR_NOTE PURPLE;
SET PROP_DISPLAY VALUE;
SET PAGE_NUMBER P56;
SET PATH_NUMBER P74;
FORCEADD UNIVERSAL_GND..1
(-3950 650);
FORCEPROP 3 LASTPIN (-3950 700) SIG_NAME GND\g
J 0
(-3940 710);
DISPLAY 0.659574 (-3940 710);
PAINT MONO (-3940 710);
DISPLAY INVISIBLE (-3940 710);
FORCEPROP 1 LAST PATH I10
J 0
(-3875 650);
DISPLAY 0.872340 (-3875 650);
PAINT AQUA (-3875 650);
DISPLAY INVISIBLE (-3875 650);
FORCEPROP 1 LAST HDL_POWER GND
J 1
(-3925 575);
DISPLAY 0.702128 (-3925 575);
PAINT GREEN (-3925 575);
DISPLAY INVISIBLE (-3925 575);
FORCEPROP 2 LAST CDS_LIB logical_power
J 0
(-3950 650);
DISPLAY INVISIBLE (-3950 650);
FORCEADD UNIVERSAL_GND..1
(-3250 -725);
FORCEPROP 3 LASTPIN (-3250 -675) SIG_NAME GND\g
J 0
(-3240 -665);
DISPLAY 0.659574 (-3240 -665);
PAINT MONO (-3240 -665);
DISPLAY INVISIBLE (-3240 -665);
FORCEPROP 1 LAST PATH I14
J 0
(-3175 -725);
DISPLAY 0.872340 (-3175 -725);
PAINT AQUA (-3175 -725);
DISPLAY INVISIBLE (-3175 -725);
FORCEPROP 1 LAST HDL_POWER GND
J 1
(-3225 -800);
DISPLAY 0.702128 (-3225 -800);
PAINT GREEN (-3225 -800);
DISPLAY INVISIBLE (-3225 -800);
FORCEPROP 2 LAST CDS_LIB logical_power
J 0
(-3250 -725);
DISPLAY INVISIBLE (-3250 -725);
FORCEADD NB695GDZ..1
(-2025 150);
FORCEPROP 2 LAST VALUE NB695GD-Z
J 0
(-2275 1100);
DISPLAY 0.510638 (-2275 1100);
PAINT SKYBLUE (-2275 1100);
FORCEPROP 2 LAST PART_TYPE SMLF
J 0
(-2275 1150);
DISPLAY 0.510638 (-2275 1150);
PAINT SKYBLUE (-2275 1150);
FORCEPROP 1 LAST MATERIAL IC
J 0
(-2269 907);
DISPLAY 0.510638 (-2269 907);
PAINT SKYBLUE (-2269 907);
FORCEPROP 1 LAST PART_NUMBER AL000695001
J 0
(-2269 1034);
DISPLAY 0.510638 (-2269 1034);
PAINT WHITE (-2269 1034);
FORCEPROP 1 LAST PATH I15
J 0
(-2025 150);
DISPLAY 0.723404 (-2025 150);
PAINT GREEN (-2025 150);
DISPLAY INVISIBLE (-2025 150);
FORCEPROP 2 LAST CDS_LIB pure_quanta
J 0
(-2025 150);
DISPLAY INVISIBLE (-2025 150);
FORCEPROP 1 LAST CDS_LMAN_SYM_OUTLINE -250,725,250,-725
J 0
(-2025 150);
DISPLAY 0.468085 (-2025 150);
PAINT GREEN (-2025 150);
DISPLAY INVISIBLE (-2025 150);
FORCEPROP 1 LAST NEEDS_NO_SIZE TRUE
J 0
(-2025 150);
DISPLAY 0.723404 (-2025 150);
PAINT GREEN (-2025 150);
DISPLAY INVISIBLE (-2025 150);
FORCEPROP 1 LAST LOCATION PU42
J 0
(-2269 1181);
DISPLAY 0.702128 (-2269 1181);
PAINT AQUA (-2269 1181);
FORCEPROP 0 LASTPIN (-2425 125) $PN 10
J 2
(-2435 135);
DISPLAY 0.680851 (-2435 135);
PAINT MONO (-2435 135);
FORCEPROP 0 LASTPIN (-1625 -525) $PN 11
J 0
(-1615 -515);
DISPLAY 0.680851 (-1615 -515);
PAINT MONO (-1615 -515);
FORCEPROP 0 LASTPIN (-1625 625) $PN 9
J 0
(-1615 635);
DISPLAY 0.680851 (-1615 635);
PAINT MONO (-1615 635);
FORCEPROP 0 LASTPIN (-2425 -375) $PN 4
J 2
(-2435 -365);
DISPLAY 0.680851 (-2435 -365);
PAINT MONO (-2435 -365);
FORCEPROP 0 LASTPIN (-2425 -275) $PN 3
J 2
(-2435 -265);
DISPLAY 0.680851 (-2435 -265);
PAINT MONO (-2435 -265);
FORCEPROP 0 LASTPIN (-2425 325) $PN 5
J 2
(-2435 335);
DISPLAY 0.680851 (-2435 335);
PAINT MONO (-2435 335);
FORCEPROP 0 LASTPIN (-2425 -175) $PN 6
J 2
(-2435 -165);
DISPLAY 0.680851 (-2435 -165);
PAINT MONO (-2435 -165);
FORCEPROP 0 LASTPIN (-2425 -525) $PN 7
J 2
(-2435 -515);
DISPLAY 0.680851 (-2435 -515);
PAINT MONO (-2435 -515);
FORCEPROP 0 LASTPIN (-1625 825) $PN 13
J 0
(-1615 835);
DISPLAY 0.680851 (-1615 835);
PAINT MONO (-1615 835);
FORCEPROP 0 LASTPIN (-1625 -475) $PN 2
J 0
(-1615 -465);
DISPLAY 0.680851 (-1615 -465);
PAINT MONO (-1615 -465);
FORCEPROP 0 LASTPIN (-1625 325) $PN 8
J 0
(-1615 335);
DISPLAY 0.680851 (-1615 335);
PAINT MONO (-1615 335);
FORCEPROP 0 LASTPIN (-2425 825) $PN 1
J 2
(-2435 835);
DISPLAY 0.680851 (-2435 835);
PAINT MONO (-2435 835);
FORCEPROP 0 LASTPIN (-1625 -375) $PN 12
J 0
(-1615 -365);
DISPLAY 0.680851 (-1615 -365);
PAINT MONO (-1615 -365);
FORCEPROP 0 LAST $SEC 1
J 0
(-2250 1225);
DISPLAY 0.680851 (-2250 1225);
PAINT MONO (-2250 1225);
DISPLAY INVISIBLE (-2250 1225);
FORCEPROP 0 LAST CDS_SEC 1
J 0
(-2250 1225);
DISPLAY 1.021277 (-2250 1225);
DISPLAY INVISIBLE (-2250 1225);
FORCEADD Q_CAP..1
(-3025 1050);
FORCEPROP 1 LAST MATERIAL X7R
J 0
(-2975 950);
DISPLAY 0.510638 (-2975 950);
PAINT SKYBLUE (-2975 950);
FORCEPROP 1 LAST PACK_TYPE 0402
J 0
(-2975 850);
DISPLAY 0.510638 (-2975 850);
PAINT SKYBLUE (-2975 850);
FORCEPROP 1 LAST TOLERANCE 10%
J 0
(-2975 1000);
DISPLAY 0.510638 (-2975 1000);
PAINT SKYBLUE (-2975 1000);
FORCEPROP 1 LAST VALUE 0.1UF
J 0
(-2975 1100);
DISPLAY 0.510638 (-2975 1100);
PAINT SKYBLUE (-2975 1100);
FORCEPROP 1 LAST VOLTAGE 25V
J 0
(-2975 1050);
DISPLAY 0.510638 (-2975 1050);
PAINT SKYBLUE (-2975 1050);
FORCEPROP 1 LAST PART_NUMBER CH4104K1B00
J 0
(-2975 900);
DISPLAY 0.510638 (-2975 900);
PAINT WHITE (-2975 900);
FORCEPROP 1 LAST PATH I16
J 0
(-2975 1200);
DISPLAY 0.978723 (-2975 1200);
PAINT WHITE (-2975 1200);
DISPLAY INVISIBLE (-2975 1200);
FORCEPROP 2 LAST CDS_LIB pure_quanta
J 0
(-3025 1050);
DISPLAY INVISIBLE (-3025 1050);
FORCEPROP 2 LAST SEC_TYPE 0402
J 0
(-2975 1250);
DISPLAY 1.021277 (-2975 1250);
DISPLAY INVISIBLE (-2975 1250);
FORCEPROP 1 LAST LOCATION PC263
J 0
(-2975 1150);
DISPLAY 0.702128 (-2975 1150);
PAINT AQUA (-2975 1150);
FORCEPROP 1 LASTPIN (-3025 1150) $PN 1
J 0
(-3015 1130);
DISPLAY 0.808511 (-3015 1130);
PAINT WHITE (-3015 1130);
FORCEPROP 1 LASTPIN (-3025 950) $PN 2
J 0
(-3015 930);
DISPLAY 0.808511 (-3015 930);
PAINT WHITE (-3015 930);
FORCEPROP 2 LAST SEC 1
J 0
(-2975 1250);
DISPLAY 0.680851 (-2975 1250);
PAINT MONO (-2975 1250);
DISPLAY INVISIBLE (-2975 1250);
FORCEADD UNIVERSAL_GND..1
(-1475 -775);
FORCEPROP 3 LASTPIN (-1475 -725) SIG_NAME GND\g
J 0
(-1465 -715);
DISPLAY 0.659574 (-1465 -715);
PAINT MONO (-1465 -715);
DISPLAY INVISIBLE (-1465 -715);
FORCEPROP 1 LAST PATH I17
J 0
(-1400 -775);
DISPLAY 0.872340 (-1400 -775);
PAINT AQUA (-1400 -775);
DISPLAY INVISIBLE (-1400 -775);
FORCEPROP 1 LAST HDL_POWER GND
J 1
(-1450 -850);
DISPLAY 0.702128 (-1450 -850);
PAINT GREEN (-1450 -850);
DISPLAY INVISIBLE (-1450 -850);
FORCEPROP 2 LAST CDS_LIB logical_power
J 0
(-1475 -775);
DISPLAY INVISIBLE (-1475 -775);
FORCEADD Q_RES..2
(-1350 1100);
FORCEPROP 1 LAST PACK_TYPE 0402LF
J 0
(-1310 925);
DISPLAY 0.510638 (-1310 925);
PAINT SKYBLUE (-1310 925);
FORCEPROP 1 LAST PART_NUMBER CS31002FB08
J 0
(-1310 975);
DISPLAY 0.510638 (-1310 975);
PAINT WHITE (-1310 975);
FORCEPROP 1 LAST VALUE 10K
J 0
(-1305 1175);
DISPLAY 0.510638 (-1305 1175);
PAINT SKYBLUE (-1305 1175);
FORCEPROP 1 LAST MATERIAL CHIP
J 0
(-1310 1025);
DISPLAY 0.510638 (-1310 1025);
PAINT SKYBLUE (-1310 1025);
FORCEPROP 1 LAST WATTAGE 1/16W
J 0
(-1310 1075);
DISPLAY 0.510638 (-1310 1075);
PAINT SKYBLUE (-1310 1075);
FORCEPROP 1 LAST TOLERANCE 1%
J 0
(-1305 1125);
DISPLAY 0.510638 (-1305 1125);
PAINT SKYBLUE (-1305 1125);
FORCEPROP 1 LAST PATH I18
J 0
(-1300 1275);
DISPLAY 0.978723 (-1300 1275);
PAINT WHITE (-1300 1275);
DISPLAY INVISIBLE (-1300 1275);
FORCEPROP 2 LAST SEC_TYPE 0402LF
J 0
(-1300 1325);
DISPLAY 1.021277 (-1300 1325);
DISPLAY INVISIBLE (-1300 1325);
FORCEPROP 2 LAST CDS_LIB pure_quanta
J 0
(-1350 1100);
DISPLAY INVISIBLE (-1350 1100);
FORCEPROP 1 LAST LOCATION PR500
J 0
(-1305 1225);
DISPLAY 0.702128 (-1305 1225);
PAINT AQUA (-1305 1225);
FORCEPROP 1 LASTPIN (-1350 1200) $PN 1
J 0
(-1345 1162);
DISPLAY 0.808511 (-1345 1162);
PAINT WHITE (-1345 1162);
FORCEPROP 1 LASTPIN (-1350 1000) $PN 2
J 0
(-1345 1010);
DISPLAY 0.808511 (-1345 1010);
PAINT WHITE (-1345 1010);
FORCEPROP 2 LAST SEC 1
J 0
(-1300 1325);
DISPLAY 0.680851 (-1300 1325);
PAINT MONO (-1300 1325);
DISPLAY INVISIBLE (-1300 1325);
FORCEADD Q_CAP..1
(-975 475);
FORCEPROP 1 LAST VOLTAGE 16V
J 0
(-900 550);
DISPLAY 0.510638 (-900 550);
PAINT SKYBLUE (-900 550);
FORCEPROP 1 LAST PACK_TYPE 0402
J 0
(-900 350);
DISPLAY 0.510638 (-900 350);
PAINT SKYBLUE (-900 350);
FORCEPROP 1 LAST VALUE 0.22UF
J 0
(-900 600);
DISPLAY 0.510638 (-900 600);
PAINT SKYBLUE (-900 600);
FORCEPROP 1 LAST TOLERANCE 10%
J 0
(-900 500);
DISPLAY 0.510638 (-900 500);
PAINT SKYBLUE (-900 500);
FORCEPROP 1 LAST MATERIAL X7R
J 0
(-900 450);
DISPLAY 0.510638 (-900 450);
PAINT SKYBLUE (-900 450);
FORCEPROP 1 LAST PART_NUMBER CH4223K1B00
J 0
(-900 400);
DISPLAY 0.510638 (-900 400);
PAINT WHITE (-900 400);
FORCEPROP 1 LAST PATH I19
J 0
(-925 625);
DISPLAY 0.978723 (-925 625);
PAINT WHITE (-925 625);
DISPLAY INVISIBLE (-925 625);
FORCEPROP 2 LAST SEC_TYPE 0402
J 0
(-925 675);
DISPLAY 1.021277 (-925 675);
DISPLAY INVISIBLE (-925 675);
FORCEPROP 2 LAST CDS_LIB pure_quanta
J 0
(-975 475);
DISPLAY INVISIBLE (-975 475);
FORCEPROP 1 LAST LOCATION PC264
J 0
(-900 650);
DISPLAY 0.702128 (-900 650);
PAINT AQUA (-900 650);
FORCEPROP 1 LASTPIN (-975 575) $PN 1
J 0
(-965 555);
DISPLAY 0.808511 (-965 555);
PAINT WHITE (-965 555);
FORCEPROP 1 LASTPIN (-975 375) $PN 2
J 0
(-965 355);
DISPLAY 0.808511 (-965 355);
PAINT WHITE (-965 355);
FORCEPROP 2 LAST SEC 1
J 0
(-925 675);
DISPLAY 0.680851 (-925 675);
PAINT MONO (-925 675);
DISPLAY INVISIBLE (-925 675);
FORCEADD VCCAUX15..1
(-5225 1650);
FORCEPROP 3 LASTPIN (-5225 1600) SIG_NAME P12V_AUX\g
J 0
(-5215 1610);
DISPLAY 0.659574 (-5215 1610);
PAINT MONO (-5215 1610);
DISPLAY INVISIBLE (-5215 1610);
FORCEPROP 1 LAST HDL_POWER P12V_AUX
J 1
(-5225 1700);
DISPLAY 0.702128 (-5225 1700);
PAINT GREEN (-5225 1700);
FORCEPROP 1 LAST PATH I2
J 0
(-5175 1675);
DISPLAY 0.872340 (-5175 1675);
PAINT AQUA (-5175 1675);
DISPLAY INVISIBLE (-5175 1675);
FORCEPROP 2 LAST CDS_LIB logical_power
J 0
(-5225 1650);
DISPLAY INVISIBLE (-5225 1650);
FORCEADD Q_CAP..1
(775 75);
FORCEPROP 1 LAST PACK_TYPE 0402
J 0
(825 -125);
DISPLAY 0.510638 (825 -125);
PAINT SKYBLUE (825 -125);
FORCEPROP 1 LAST MATERIAL X7R
J 0
(825 -25);
DISPLAY 0.510638 (825 -25);
PAINT SKYBLUE (825 -25);
FORCEPROP 1 LAST PART_NUMBER CH4104K1B00
J 0
(825 -75);
DISPLAY 0.510638 (825 -75);
PAINT WHITE (825 -75);
FORCEPROP 1 LAST VALUE 0.1UF
J 0
(825 125);
DISPLAY 0.510638 (825 125);
PAINT SKYBLUE (825 125);
FORCEPROP 1 LAST TOLERANCE 10%
J 0
(825 25);
DISPLAY 0.510638 (825 25);
PAINT SKYBLUE (825 25);
FORCEPROP 1 LAST VOLTAGE 25V
J 0
(825 75);
DISPLAY 0.510638 (825 75);
PAINT SKYBLUE (825 75);
FORCEPROP 1 LAST PATH I23
J 0
(825 225);
DISPLAY 0.978723 (825 225);
PAINT WHITE (825 225);
DISPLAY INVISIBLE (825 225);
FORCEPROP 2 LAST SEC_TYPE 0402
J 0
(825 275);
DISPLAY 1.021277 (825 275);
DISPLAY INVISIBLE (825 275);
FORCEPROP 2 LAST CDS_LIB pure_quanta
J 0
(775 75);
DISPLAY INVISIBLE (775 75);
FORCEPROP 1 LAST LOCATION PC266
J 0
(825 175);
DISPLAY 0.702128 (825 175);
PAINT AQUA (825 175);
FORCEPROP 1 LASTPIN (775 175) $PN 1
J 0
(785 155);
DISPLAY 0.808511 (785 155);
PAINT WHITE (785 155);
FORCEPROP 1 LASTPIN (775 -25) $PN 2
J 0
(785 -45);
DISPLAY 0.808511 (785 -45);
PAINT WHITE (785 -45);
FORCEPROP 2 LAST SEC 1
J 0
(825 275);
DISPLAY 0.680851 (825 275);
PAINT MONO (825 275);
DISPLAY INVISIBLE (825 275);
FORCEADD Q_CAP..1
(1325 75);
FORCEPROP 1 LAST MATERIAL X6S
J 0
(1375 -25);
DISPLAY 0.510638 (1375 -25);
PAINT SKYBLUE (1375 -25);
FORCEPROP 1 LAST PACK_TYPE 0805
J 0
(1375 -125);
DISPLAY 0.510638 (1375 -125);
PAINT SKYBLUE (1375 -125);
FORCEPROP 1 LAST TOLERANCE 20%
J 0
(1375 25);
DISPLAY 0.510638 (1375 25);
PAINT SKYBLUE (1375 25);
FORCEPROP 1 LAST VOLTAGE 4V
J 0
(1375 75);
DISPLAY 0.510638 (1375 75);
PAINT SKYBLUE (1375 75);
FORCEPROP 1 LAST VALUE 22UF
J 0
(1375 125);
DISPLAY 0.510638 (1375 125);
PAINT SKYBLUE (1375 125);
FORCEPROP 1 LAST PATH I24
J 0
(1375 225);
DISPLAY 0.978723 (1375 225);
PAINT WHITE (1375 225);
DISPLAY INVISIBLE (1375 225);
FORCEPROP 1 LAST PART_NUMBER TMP_QCH622KMEA01
J 0
(1375 -75);
DISPLAY 0.510638 (1375 -75);
PAINT WHITE (1375 -75);
DISPLAY INVISIBLE (1375 -75);
FORCEPROP 2 LAST CDS_LIB pure_quanta
J 0
(1325 75);
DISPLAY INVISIBLE (1325 75);
FORCEPROP 2 LAST SEC_TYPE 0805
J 0
(1375 275);
DISPLAY 1.021277 (1375 275);
DISPLAY INVISIBLE (1375 275);
FORCEPROP 1 LAST LOCATION PC267
J 0
(1375 175);
DISPLAY 0.702128 (1375 175);
PAINT AQUA (1375 175);
FORCEPROP 1 LASTPIN (1325 175) $PN 1
J 0
(1335 155);
DISPLAY 0.808511 (1335 155);
PAINT WHITE (1335 155);
FORCEPROP 1 LASTPIN (1325 -25) $PN 2
J 0
(1335 -45);
DISPLAY 0.808511 (1335 -45);
PAINT WHITE (1335 -45);
FORCEPROP 2 LAST SEC 1
J 0
(1375 275);
DISPLAY 0.680851 (1375 275);
PAINT MONO (1375 275);
DISPLAY INVISIBLE (1375 275);
FORCEADD Q_CAP..1
(1575 75);
FORCEPROP 1 LAST MATERIAL X6S
J 0
(1625 -25);
DISPLAY 0.510638 (1625 -25);
PAINT SKYBLUE (1625 -25);
FORCEPROP 1 LAST VALUE 22UF
J 0
(1625 125);
DISPLAY 0.510638 (1625 125);
PAINT SKYBLUE (1625 125);
FORCEPROP 1 LAST TOLERANCE 20%
J 0
(1625 25);
DISPLAY 0.510638 (1625 25);
PAINT SKYBLUE (1625 25);
FORCEPROP 1 LAST PACK_TYPE 0805
J 0
(1625 -125);
DISPLAY 0.510638 (1625 -125);
PAINT SKYBLUE (1625 -125);
FORCEPROP 1 LAST VOLTAGE 4V
J 0
(1625 75);
DISPLAY 0.510638 (1625 75);
PAINT SKYBLUE (1625 75);
FORCEPROP 1 LAST PATH I25
J 0
(1625 225);
DISPLAY 0.978723 (1625 225);
PAINT WHITE (1625 225);
DISPLAY INVISIBLE (1625 225);
FORCEPROP 1 LAST PART_NUMBER TMP_QCH622KMEA01
J 0
(1625 -75);
DISPLAY 0.510638 (1625 -75);
PAINT WHITE (1625 -75);
DISPLAY INVISIBLE (1625 -75);
FORCEPROP 2 LAST CDS_LIB pure_quanta
J 0
(1575 75);
DISPLAY INVISIBLE (1575 75);
FORCEPROP 2 LAST SEC_TYPE 0805
J 0
(1625 275);
DISPLAY 1.021277 (1625 275);
DISPLAY INVISIBLE (1625 275);
FORCEPROP 1 LAST LOCATION PC268
J 0
(1625 175);
DISPLAY 0.702128 (1625 175);
PAINT AQUA (1625 175);
FORCEPROP 1 LASTPIN (1575 175) $PN 1
J 0
(1585 155);
DISPLAY 0.808511 (1585 155);
PAINT WHITE (1585 155);
FORCEPROP 1 LASTPIN (1575 -25) $PN 2
J 0
(1585 -45);
DISPLAY 0.808511 (1585 -45);
PAINT WHITE (1585 -45);
FORCEPROP 2 LAST SEC 1
J 0
(1625 275);
DISPLAY 0.680851 (1625 275);
PAINT MONO (1625 275);
DISPLAY INVISIBLE (1625 275);
FORCEADD UNIVERSAL_GND..1
(2075 -250);
FORCEPROP 3 LASTPIN (2075 -200) SIG_NAME GND\g
J 0
(2085 -190);
DISPLAY 0.659574 (2085 -190);
PAINT MONO (2085 -190);
DISPLAY INVISIBLE (2085 -190);
FORCEPROP 1 LAST PATH I27
J 0
(2150 -250);
DISPLAY 0.872340 (2150 -250);
PAINT AQUA (2150 -250);
DISPLAY INVISIBLE (2150 -250);
FORCEPROP 1 LAST HDL_POWER GND
J 1
(2100 -325);
DISPLAY 0.702128 (2100 -325);
PAINT GREEN (2100 -325);
DISPLAY INVISIBLE (2100 -325);
FORCEPROP 2 LAST CDS_LIB logical_power
J 0
(2075 -250);
DISPLAY INVISIBLE (2075 -250);
FORCEADD Q_CAP..1
(1825 75);
FORCEPROP 1 LAST MATERIAL X6S
J 0
(1875 -25);
DISPLAY 0.510638 (1875 -25);
PAINT SKYBLUE (1875 -25);
FORCEPROP 1 LAST VALUE 22UF
J 0
(1875 125);
DISPLAY 0.510638 (1875 125);
PAINT SKYBLUE (1875 125);
FORCEPROP 1 LAST TOLERANCE 20%
J 0
(1875 25);
DISPLAY 0.510638 (1875 25);
PAINT SKYBLUE (1875 25);
FORCEPROP 1 LAST PACK_TYPE 0805
J 0
(1875 -125);
DISPLAY 0.510638 (1875 -125);
PAINT SKYBLUE (1875 -125);
FORCEPROP 1 LAST VOLTAGE 4V
J 0
(1875 75);
DISPLAY 0.510638 (1875 75);
PAINT SKYBLUE (1875 75);
FORCEPROP 1 LAST PATH I28
J 0
(1875 225);
DISPLAY 0.978723 (1875 225);
PAINT WHITE (1875 225);
DISPLAY INVISIBLE (1875 225);
FORCEPROP 1 LAST PART_NUMBER TMP_QCH622KMEA01
J 0
(1875 -75);
DISPLAY 0.510638 (1875 -75);
PAINT WHITE (1875 -75);
DISPLAY INVISIBLE (1875 -75);
FORCEPROP 2 LAST CDS_LIB pure_quanta
J 0
(1825 75);
DISPLAY INVISIBLE (1825 75);
FORCEPROP 2 LAST SEC_TYPE 0805
J 0
(1875 275);
DISPLAY 1.021277 (1875 275);
DISPLAY INVISIBLE (1875 275);
FORCEPROP 1 LAST LOCATION PC269
J 0
(1875 175);
DISPLAY 0.702128 (1875 175);
PAINT AQUA (1875 175);
FORCEPROP 1 LASTPIN (1825 175) $PN 1
J 0
(1835 155);
DISPLAY 0.808511 (1835 155);
PAINT WHITE (1835 155);
FORCEPROP 1 LASTPIN (1825 -25) $PN 2
J 0
(1835 -45);
DISPLAY 0.808511 (1835 -45);
PAINT WHITE (1835 -45);
FORCEPROP 2 LAST SEC 1
J 0
(1875 275);
DISPLAY 0.680851 (1875 275);
PAINT MONO (1875 275);
DISPLAY INVISIBLE (1875 275);
FORCEADD Q_CAP..1
(2075 75);
FORCEPROP 1 LAST MATERIAL X6S
J 0
(2125 -25);
DISPLAY 0.510638 (2125 -25);
PAINT SKYBLUE (2125 -25);
FORCEPROP 1 LAST PART_NUMBER TMP_QCH622KMEA01
J 0
(2125 -75);
DISPLAY 0.510638 (2125 -75);
PAINT WHITE (2125 -75);
FORCEPROP 1 LAST VALUE 22UF
J 0
(2125 125);
DISPLAY 0.510638 (2125 125);
PAINT SKYBLUE (2125 125);
FORCEPROP 1 LAST TOLERANCE 20%
J 0
(2125 25);
DISPLAY 0.510638 (2125 25);
PAINT SKYBLUE (2125 25);
FORCEPROP 1 LAST PACK_TYPE 0805
J 0
(2125 -125);
DISPLAY 0.510638 (2125 -125);
PAINT SKYBLUE (2125 -125);
FORCEPROP 1 LAST VOLTAGE 4V
J 0
(2125 75);
DISPLAY 0.510638 (2125 75);
PAINT SKYBLUE (2125 75);
FORCEPROP 1 LAST PATH I29
J 0
(2125 225);
DISPLAY 0.978723 (2125 225);
PAINT WHITE (2125 225);
DISPLAY INVISIBLE (2125 225);
FORCEPROP 2 LAST CDS_LIB pure_quanta
J 0
(2075 75);
DISPLAY INVISIBLE (2075 75);
FORCEPROP 2 LAST SEC_TYPE 0805
J 0
(2125 275);
DISPLAY 1.021277 (2125 275);
DISPLAY INVISIBLE (2125 275);
FORCEPROP 1 LAST LOCATION PC270
J 0
(2125 175);
DISPLAY 0.702128 (2125 175);
PAINT AQUA (2125 175);
FORCEPROP 1 LASTPIN (2075 175) $PN 1
J 0
(2085 155);
DISPLAY 0.808511 (2085 155);
PAINT WHITE (2085 155);
FORCEPROP 1 LASTPIN (2075 -25) $PN 2
J 0
(2085 -45);
DISPLAY 0.808511 (2085 -45);
PAINT WHITE (2085 -45);
FORCEPROP 2 LAST SEC 1
J 0
(2125 275);
DISPLAY 0.680851 (2125 275);
PAINT MONO (2125 275);
DISPLAY INVISIBLE (2125 275);
FORCEADD VCCAUX15..1
(2725 450);
FORCEPROP 3 LASTPIN (2725 400) SIG_NAME P1V0_AUX\g
J 0
(2735 410);
DISPLAY 0.659574 (2735 410);
PAINT MONO (2735 410);
DISPLAY INVISIBLE (2735 410);
FORCEPROP 1 LAST HDL_POWER P1V0_AUX
J 1
(2725 500);
DISPLAY 0.702128 (2725 500);
PAINT GREEN (2725 500);
FORCEPROP 1 LAST PATH I30
J 0
(2775 475);
DISPLAY 0.872340 (2775 475);
PAINT AQUA (2775 475);
DISPLAY INVISIBLE (2775 475);
FORCEPROP 2 LAST CDS_LIB logical_power
J 0
(2725 450);
DISPLAY INVISIBLE (2725 450);
FORCEADD Q_INDUCTOR..1
(-4650 1325);
FORCEPROP 1 LAST PART_NUMBER CX220TN1001
J 0
(-4850 1250);
DISPLAY 0.510638 (-4850 1250);
PAINT WHITE (-4850 1250);
FORCEPROP 2 LAST PACK_TYPE SMLF
J 0
(-4725 1075);
DISPLAY 0.510638 (-4725 1075);
PAINT SKYBLUE (-4725 1075);
FORCEPROP 1 LAST MATERIAL IND
J 0
(-4750 1200);
DISPLAY 0.510638 (-4750 1200);
PAINT SKYBLUE (-4750 1200);
FORCEPROP 2 LAST VALUE BLM18SN220TN1D/8000MA
J 0
(-5000 1150);
DISPLAY 0.510638 (-5000 1150);
PAINT SKYBLUE (-5000 1150);
FORCEPROP 2 LAST CDS_LIB pure_quanta
J 0
(-4650 1325);
DISPLAY INVISIBLE (-4650 1325);
FORCEPROP 1 LAST NEEDS_NO_SIZE TRUE
J 0
(-4650 1325);
DISPLAY 0.468085 (-4650 1325);
PAINT GREEN (-4650 1325);
DISPLAY INVISIBLE (-4650 1325);
FORCEPROP 1 LAST PATH I34
J 0
(-4575 1380);
DISPLAY 0.723404 (-4575 1380);
PAINT GREEN (-4575 1380);
DISPLAY INVISIBLE (-4575 1380);
FORCEPROP 1 LAST LOCATION PL32
J 0
(-4750 1375);
DISPLAY 0.702128 (-4750 1375);
PAINT AQUA (-4750 1375);
FORCEPROP 0 LASTPIN (-4750 1300) $PN 1
J 2
(-4760 1310);
DISPLAY 0.808511 (-4760 1310);
PAINT WHITE (-4760 1310);
FORCEPROP 0 LASTPIN (-4550 1300) $PN 2
J 0
(-4540 1310);
DISPLAY 0.808511 (-4540 1310);
PAINT WHITE (-4540 1310);
FORCEPROP 0 LAST $SEC 1
J 0
(-4750 1425);
DISPLAY 0.680851 (-4750 1425);
PAINT MONO (-4750 1425);
DISPLAY INVISIBLE (-4750 1425);
FORCEPROP 0 LAST CDS_SEC 1
J 0
(-4750 1425);
DISPLAY 1.021277 (-4750 1425);
DISPLAY INVISIBLE (-4750 1425);
FORCEADD Q_INDUCTOR..1
(275 350);
FORCEPROP 1 LAST MATERIAL IND
J 0
(150 405);
DISPLAY 0.510638 (150 405);
PAINT SKYBLUE (150 405);
FORCEPROP 2 LAST PACK_TYPE SMLF
J 0
(-25 250);
DISPLAY 0.510638 (-25 250);
PAINT SKYBLUE (-25 250);
FORCEPROP 1 LAST PART_NUMBER CV-10B0MZ13
J 0
(150 460);
DISPLAY 0.510638 (150 460);
PAINT WHITE (150 460);
FORCEPROP 0 LAST DCR DCR=9MOHM
J 0
(150 150);
DISPLAY 0.638298 (150 150);
PAINT WHITE (150 150);
FORCEPROP 2 LAST VALUE 1UH
J 0
(200 250);
DISPLAY 0.510638 (200 250);
PAINT SKYBLUE (200 250);
FORCEPROP 1 LAST PATH I37
J 0
(350 405);
DISPLAY 0.723404 (350 405);
PAINT GREEN (350 405);
DISPLAY INVISIBLE (350 405);
FORCEPROP 2 LAST CDS_LIB pure_quanta
J 0
(275 350);
DISPLAY INVISIBLE (275 350);
FORCEPROP 1 LAST NEEDS_NO_SIZE TRUE
J 0
(275 350);
DISPLAY 0.468085 (275 350);
PAINT GREEN (275 350);
DISPLAY INVISIBLE (275 350);
FORCEPROP 1 LAST LOCATION PL33
J 0
(150 510);
DISPLAY 0.702128 (150 510);
PAINT AQUA (150 510);
FORCEPROP 0 LASTPIN (175 325) $PN 1
J 2
(165 335);
DISPLAY 0.808511 (165 335);
PAINT WHITE (165 335);
FORCEPROP 0 LASTPIN (375 325) $PN 2
J 0
(385 335);
DISPLAY 0.808511 (385 335);
PAINT WHITE (385 335);
FORCEPROP 0 LAST $SEC 1
J 0
(150 550);
DISPLAY 0.680851 (150 550);
PAINT MONO (150 550);
DISPLAY INVISIBLE (150 550);
FORCEPROP 0 LAST CDS_SEC 1
J 0
(150 550);
DISPLAY 1.021277 (150 550);
DISPLAY INVISIBLE (150 550);
FORCEADD VCCAUX15..1
(-1350 1375);
FORCEPROP 3 LASTPIN (-1350 1325) SIG_NAME P3V3_AUX\g
J 0
(-1340 1335);
DISPLAY 0.659574 (-1340 1335);
PAINT MONO (-1340 1335);
DISPLAY INVISIBLE (-1340 1335);
FORCEPROP 1 LAST HDL_POWER P3V3_AUX
J 1
(-1350 1425);
DISPLAY 0.702128 (-1350 1425);
PAINT GREEN (-1350 1425);
FORCEPROP 1 LAST PATH I38
J 0
(-1300 1400);
DISPLAY 0.872340 (-1300 1400);
PAINT AQUA (-1300 1400);
DISPLAY INVISIBLE (-1300 1400);
FORCEPROP 2 LAST CDS_LIB logical_power
J 0
(-1350 1375);
DISPLAY INVISIBLE (-1350 1375);
FORCEADD UNIVERSAL_GND..1
(-4025 -800);
FORCEPROP 3 LASTPIN (-4025 -750) SIG_NAME GND\g
J 0
(-4015 -740);
DISPLAY 0.659574 (-4015 -740);
PAINT MONO (-4015 -740);
DISPLAY INVISIBLE (-4015 -740);
FORCEPROP 1 LAST PATH I4
J 0
(-3950 -800);
DISPLAY 0.872340 (-3950 -800);
PAINT AQUA (-3950 -800);
DISPLAY INVISIBLE (-3950 -800);
FORCEPROP 1 LAST HDL_POWER GND
J 1
(-4000 -875);
DISPLAY 0.702128 (-4000 -875);
PAINT GREEN (-4000 -875);
DISPLAY INVISIBLE (-4000 -875);
FORCEPROP 2 LAST CDS_LIB logical_power
J 0
(-4025 -800);
DISPLAY INVISIBLE (-4025 -800);
FORCEADD Q_CAP..1
(-3975 1050);
FORCEPROP 1 LAST TOLERANCE 10%
J 0
(-3925 1000);
DISPLAY 0.510638 (-3925 1000);
PAINT SKYBLUE (-3925 1000);
FORCEPROP 1 LAST VOLTAGE 25V
J 0
(-3925 1050);
DISPLAY 0.510638 (-3925 1050);
PAINT SKYBLUE (-3925 1050);
FORCEPROP 1 LAST VALUE 10UF
J 0
(-3925 1100);
DISPLAY 0.510638 (-3925 1100);
PAINT SKYBLUE (-3925 1100);
FORCEPROP 1 LAST PACK_TYPE C0805
J 0
(-3925 850);
DISPLAY 0.510638 (-3925 850);
PAINT SKYBLUE (-3925 850);
FORCEPROP 1 LAST PART_NUMBER CH6104KEA00
J 0
(-3925 900);
DISPLAY 0.510638 (-3925 900);
PAINT WHITE (-3925 900);
FORCEPROP 1 LAST MATERIAL X6S
J 0
(-3925 950);
DISPLAY 0.510638 (-3925 950);
PAINT SKYBLUE (-3925 950);
FORCEPROP 1 LAST PATH I43
J 0
(-3925 1200);
DISPLAY 0.978723 (-3925 1200);
PAINT WHITE (-3925 1200);
DISPLAY INVISIBLE (-3925 1200);
FORCEPROP 2 LAST CDS_LIB pure_quanta
J 0
(-3975 1050);
DISPLAY INVISIBLE (-3975 1050);
FORCEPROP 1 LAST LOCATION PC262
J 0
(-3925 1150);
DISPLAY 0.702128 (-3925 1150);
PAINT AQUA (-3925 1150);
FORCEPROP 0 LAST $SEC 1
J 0
(-3925 1200);
DISPLAY 0.680851 (-3925 1200);
PAINT MONO (-3925 1200);
DISPLAY INVISIBLE (-3925 1200);
FORCEPROP 0 LAST CDS_SEC 1
J 0
(-3925 1200);
DISPLAY 1.021277 (-3925 1200);
DISPLAY INVISIBLE (-3925 1200);
FORCEPROP 1 LASTPIN (-3975 1150) $PN 1
J 0
(-3965 1130);
DISPLAY 0.808511 (-3965 1130);
PAINT WHITE (-3965 1130);
DISPLAY INVISIBLE (-3965 1130);
FORCEPROP 1 LASTPIN (-3975 950) $PN 2
J 0
(-3965 930);
DISPLAY 0.808511 (-3965 930);
PAINT WHITE (-3965 930);
DISPLAY INVISIBLE (-3965 930);
FORCEADD Q_CAP..1
(-3575 1050);
FORCEPROP 1 LAST TOLERANCE 10%
J 0
(-3525 1000);
DISPLAY 0.510638 (-3525 1000);
PAINT SKYBLUE (-3525 1000);
FORCEPROP 1 LAST VOLTAGE 25V
J 0
(-3525 1050);
DISPLAY 0.510638 (-3525 1050);
PAINT SKYBLUE (-3525 1050);
FORCEPROP 1 LAST VALUE 10UF
J 0
(-3525 1100);
DISPLAY 0.510638 (-3525 1100);
PAINT SKYBLUE (-3525 1100);
FORCEPROP 1 LAST PACK_TYPE C0805
J 0
(-3525 850);
DISPLAY 0.510638 (-3525 850);
PAINT SKYBLUE (-3525 850);
FORCEPROP 1 LAST PART_NUMBER CH6104KEA00
J 0
(-3525 900);
DISPLAY 0.510638 (-3525 900);
PAINT WHITE (-3525 900);
FORCEPROP 1 LAST MATERIAL X6S
J 0
(-3525 950);
DISPLAY 0.510638 (-3525 950);
PAINT SKYBLUE (-3525 950);
FORCEPROP 1 LAST PATH I44
J 0
(-3525 1200);
DISPLAY 0.978723 (-3525 1200);
PAINT WHITE (-3525 1200);
DISPLAY INVISIBLE (-3525 1200);
FORCEPROP 2 LAST CDS_LIB pure_quanta
J 0
(-3575 1050);
DISPLAY INVISIBLE (-3575 1050);
FORCEPROP 1 LAST LOCATION PC261
J 0
(-3525 1150);
DISPLAY 0.702128 (-3525 1150);
PAINT AQUA (-3525 1150);
FORCEPROP 0 LAST $SEC 1
J 0
(-3525 1200);
DISPLAY 0.680851 (-3525 1200);
PAINT MONO (-3525 1200);
DISPLAY INVISIBLE (-3525 1200);
FORCEPROP 0 LAST CDS_SEC 1
J 0
(-3525 1200);
DISPLAY 1.021277 (-3525 1200);
DISPLAY INVISIBLE (-3525 1200);
FORCEPROP 1 LASTPIN (-3575 1150) $PN 1
J 0
(-3565 1130);
DISPLAY 0.808511 (-3565 1130);
PAINT WHITE (-3565 1130);
DISPLAY INVISIBLE (-3565 1130);
FORCEPROP 1 LASTPIN (-3575 950) $PN 2
J 0
(-3565 930);
DISPLAY 0.808511 (-3565 930);
PAINT WHITE (-3565 930);
DISPLAY INVISIBLE (-3565 930);
FORCEADD VCCAUX15..1
(-2375 -1325);
FORCEPROP 3 LASTPIN (-2375 -1375) SIG_NAME PVCC2_AUX\g
J 0
(-2365 -1365);
DISPLAY 0.659574 (-2365 -1365);
PAINT MONO (-2365 -1365);
DISPLAY INVISIBLE (-2365 -1365);
FORCEPROP 1 LAST HDL_POWER PVCC2_AUX
J 1
(-2375 -1275);
DISPLAY 0.702128 (-2375 -1275);
PAINT GREEN (-2375 -1275);
FORCEPROP 1 LAST PATH I45
J 0
(-2325 -1300);
DISPLAY 0.872340 (-2325 -1300);
PAINT AQUA (-2325 -1300);
DISPLAY INVISIBLE (-2325 -1300);
FORCEPROP 2 LAST CDS_LIB logical_power
J 0
(-2375 -1325);
DISPLAY INVISIBLE (-2375 -1325);
FORCEADD VCCAUX15..1
(-2375 -1650);
FORCEPROP 3 LASTPIN (-2375 -1700) SIG_NAME PVCC2_AUX\g
J 0
(-2365 -1690);
DISPLAY 0.659574 (-2365 -1690);
PAINT MONO (-2365 -1690);
DISPLAY INVISIBLE (-2365 -1690);
FORCEPROP 1 LAST HDL_POWER PVCC2_AUX
J 1
(-2375 -1600);
DISPLAY 0.702128 (-2375 -1600);
PAINT GREEN (-2375 -1600);
FORCEPROP 1 LAST PATH I46
J 0
(-2325 -1625);
DISPLAY 0.872340 (-2325 -1625);
PAINT AQUA (-2325 -1625);
DISPLAY INVISIBLE (-2325 -1625);
FORCEPROP 2 LAST CDS_LIB logical_power
J 0
(-2375 -1650);
DISPLAY INVISIBLE (-2375 -1650);
FORCEADD Q_RES..1
(-3100 -1475);
FORCEPROP 1 LAST PART_NUMBER CS00002JB13
J 0
(-2950 -1450);
DISPLAY 0.510638 (-2950 -1450);
PAINT WHITE (-2950 -1450);
FORCEPROP 1 LAST PACK_TYPE 0402LF
J 0
(-2975 -1625);
DISPLAY 0.510638 (-2975 -1625);
PAINT SKYBLUE (-2975 -1625);
FORCEPROP 1 LAST MATERIAL CHIP
J 0
(-3100 -1625);
DISPLAY 0.510638 (-3100 -1625);
PAINT SKYBLUE (-3100 -1625);
FORCEPROP 1 LAST WATTAGE 1/16W
J 2
(-3125 -1625);
DISPLAY 0.510638 (-3125 -1625);
PAINT SKYBLUE (-3125 -1625);
FORCEPROP 1 LAST TOLERANCE 5%
J 0
(-3100 -1575);
DISPLAY 0.510638 (-3100 -1575);
PAINT SKYBLUE (-3100 -1575);
FORCEPROP 1 LAST VALUE 0
J 2
(-3125 -1575);
DISPLAY 0.510638 (-3125 -1575);
PAINT SKYBLUE (-3125 -1575);
FORCEPROP 1 LAST PATH I47
J 0
(-3150 -1325);
DISPLAY 0.978723 (-3150 -1325);
PAINT WHITE (-3150 -1325);
DISPLAY INVISIBLE (-3150 -1325);
FORCEPROP 2 LAST CDS_LIB pure_quanta
J 0
(-3100 -1475);
DISPLAY INVISIBLE (-3100 -1475);
FORCEPROP 1 LAST LOCATION PR193
J 0
(-3375 -1450);
DISPLAY 0.702128 (-3375 -1450);
PAINT AQUA (-3375 -1450);
FORCEPROP 0 LAST $SEC 1
J 0
(-3375 -1400);
DISPLAY 0.680851 (-3375 -1400);
PAINT MONO (-3375 -1400);
DISPLAY INVISIBLE (-3375 -1400);
FORCEPROP 0 LAST CDS_SEC 1
J 0
(-3375 -1400);
DISPLAY 1.021277 (-3375 -1400);
DISPLAY INVISIBLE (-3375 -1400);
FORCEPROP 1 LASTPIN (-3200 -1475) $PN 1
J 0
(-3188 -1463);
DISPLAY 0.808511 (-3188 -1463);
PAINT WHITE (-3188 -1463);
DISPLAY INVISIBLE (-3188 -1463);
FORCEPROP 1 LASTPIN (-3000 -1475) $PN 2
J 0
(-3038 -1463);
DISPLAY 0.808511 (-3038 -1463);
PAINT WHITE (-3038 -1463);
DISPLAY INVISIBLE (-3038 -1463);
FORCEADD Q_RES..1
(-3100 -1800);
FORCEPROP 1 LAST PART_NUMBER CS00002JB13
J 0
(-2950 -1775);
DISPLAY 0.510638 (-2950 -1775);
PAINT WHITE (-2950 -1775);
FORCEPROP 1 LAST PACK_TYPE 0402LF
J 0
(-2975 -1950);
DISPLAY 0.510638 (-2975 -1950);
PAINT SKYBLUE (-2975 -1950);
FORCEPROP 1 LAST WATTAGE 1/16W
J 2
(-3125 -1950);
DISPLAY 0.510638 (-3125 -1950);
PAINT SKYBLUE (-3125 -1950);
FORCEPROP 1 LAST MATERIAL EMPTY
J 0
(-3100 -1950);
DISPLAY 0.510638 (-3100 -1950);
PAINT RED (-3100 -1950);
FORCEPROP 1 LAST TOLERANCE 5%
J 0
(-3100 -1900);
DISPLAY 0.510638 (-3100 -1900);
PAINT SKYBLUE (-3100 -1900);
FORCEPROP 1 LAST VALUE 0
J 2
(-3125 -1900);
DISPLAY 0.510638 (-3125 -1900);
PAINT SKYBLUE (-3125 -1900);
FORCEPROP 1 LAST PATH I48
J 0
(-3150 -1650);
DISPLAY 0.978723 (-3150 -1650);
PAINT WHITE (-3150 -1650);
DISPLAY INVISIBLE (-3150 -1650);
FORCEPROP 2 LAST CDS_LIB pure_quanta
J 0
(-3100 -1800);
DISPLAY INVISIBLE (-3100 -1800);
FORCEPROP 1 LAST LOCATION PR205
J 0
(-3375 -1775);
DISPLAY 0.702128 (-3375 -1775);
PAINT AQUA (-3375 -1775);
FORCEPROP 0 LAST $SEC 1
J 0
(-3375 -1725);
DISPLAY 0.680851 (-3375 -1725);
PAINT MONO (-3375 -1725);
DISPLAY INVISIBLE (-3375 -1725);
FORCEPROP 0 LAST CDS_SEC 1
J 0
(-3375 -1725);
DISPLAY 1.021277 (-3375 -1725);
DISPLAY INVISIBLE (-3375 -1725);
FORCEPROP 1 LASTPIN (-3200 -1800) $PN 1
J 0
(-3188 -1788);
DISPLAY 0.808511 (-3188 -1788);
PAINT WHITE (-3188 -1788);
DISPLAY INVISIBLE (-3188 -1788);
FORCEPROP 1 LASTPIN (-3000 -1800) $PN 2
J 0
(-3038 -1788);
DISPLAY 0.808511 (-3038 -1788);
PAINT WHITE (-3038 -1788);
DISPLAY INVISIBLE (-3038 -1788);
FORCEADD VCCAUX15..1
(-3650 -1350);
FORCEPROP 3 LASTPIN (-3650 -1400) SIG_NAME P3V3_AUX\g
J 0
(-3640 -1390);
DISPLAY 0.659574 (-3640 -1390);
PAINT MONO (-3640 -1390);
DISPLAY INVISIBLE (-3640 -1390);
FORCEPROP 1 LAST HDL_POWER P3V3_AUX
J 1
(-3650 -1300);
DISPLAY 0.702128 (-3650 -1300);
PAINT GREEN (-3650 -1300);
FORCEPROP 1 LAST PATH I49
J 0
(-3600 -1325);
DISPLAY 0.872340 (-3600 -1325);
PAINT AQUA (-3600 -1325);
DISPLAY INVISIBLE (-3600 -1325);
FORCEPROP 2 LAST CDS_LIB logical_power
J 0
(-3650 -1350);
DISPLAY INVISIBLE (-3650 -1350);
FORCEADD UNIVERSAL_GND..1
(-2950 -1100);
FORCEPROP 3 LASTPIN (-2950 -1050) SIG_NAME GND\g
J 0
(-2940 -1040);
DISPLAY 0.659574 (-2940 -1040);
PAINT MONO (-2940 -1040);
DISPLAY INVISIBLE (-2940 -1040);
FORCEPROP 1 LAST PATH I5
J 0
(-2875 -1100);
DISPLAY 0.872340 (-2875 -1100);
PAINT AQUA (-2875 -1100);
DISPLAY INVISIBLE (-2875 -1100);
FORCEPROP 1 LAST HDL_POWER GND
J 1
(-2925 -1175);
DISPLAY 0.702128 (-2925 -1175);
PAINT GREEN (-2925 -1175);
DISPLAY INVISIBLE (-2925 -1175);
FORCEPROP 2 LAST CDS_LIB logical_power
J 0
(-2950 -1100);
DISPLAY INVISIBLE (-2950 -1100);
FORCEADD VCCAUX15..1
(-3650 -1700);
FORCEPROP 3 LASTPIN (-3650 -1750) SIG_NAME P5V_AUX\g
J 0
(-3640 -1740);
DISPLAY 0.659574 (-3640 -1740);
PAINT MONO (-3640 -1740);
DISPLAY INVISIBLE (-3640 -1740);
FORCEPROP 1 LAST HDL_POWER P5V_AUX
J 1
(-3650 -1650);
DISPLAY 0.702128 (-3650 -1650);
PAINT GREEN (-3650 -1650);
FORCEPROP 1 LAST PATH I50
J 0
(-3600 -1675);
DISPLAY 0.872340 (-3600 -1675);
PAINT AQUA (-3600 -1675);
DISPLAY INVISIBLE (-3600 -1675);
FORCEPROP 2 LAST CDS_LIB logical_power
J 0
(-3650 -1700);
DISPLAY INVISIBLE (-3650 -1700);
FORCEADD Q_CAP..1
(-525 625);
FORCEPROP 1 LAST VALUE 0.001UF
J 0
(-475 675);
DISPLAY 0.787234 (-475 675);
FORCEPROP 1 LAST VOLTAGE 50V
J 0
(-475 625);
DISPLAY 0.787234 (-475 625);
FORCEPROP 1 LAST MATERIAL EMPTY
J 0
(-475 525);
DISPLAY 0.787234 (-475 525);
FORCEPROP 1 LAST TOLERANCE 10%
J 0
(-475 575);
DISPLAY 0.787234 (-475 575);
FORCEPROP 1 LAST PACK_TYPE C0402
J 0
(-475 425);
DISPLAY 0.787234 (-475 425);
FORCEPROP 1 LAST PART_NUMBER CH30106KB19
J 0
(-475 475);
DISPLAY 0.787234 (-475 475);
FORCEPROP 2 LAST CDS_LIB pure_quanta
J 0
(-525 625);
DISPLAY INVISIBLE (-525 625);
FORCEPROP 1 LAST PATH I51
J 0
(-475 775);
DISPLAY 0.978723 (-475 775);
PAINT WHITE (-475 775);
DISPLAY INVISIBLE (-475 775);
FORCEPROP 1 LAST LOCATION C156
J 0
(-475 725);
DISPLAY 0.787234 (-475 725);
FORCEPROP 1 LASTPIN (-525 725) $PN 1
J 0
(-515 705);
DISPLAY 0.787234 (-515 705);
PAINT MONO (-515 705);
FORCEPROP 1 LASTPIN (-525 525) $PN 2
J 0
(-515 505);
DISPLAY 0.787234 (-515 505);
PAINT MONO (-515 505);
FORCEPROP 0 LAST $SEC 1
J 0
(-475 775);
DISPLAY 0.680851 (-475 775);
PAINT MONO (-475 775);
DISPLAY INVISIBLE (-475 775);
FORCEPROP 0 LAST CDS_SEC 1
J 0
(-475 775);
DISPLAY 0.680851 (-475 775);
DISPLAY INVISIBLE (-475 775);
FORCEADD UNIVERSAL_GND..1
(-525 425);
FORCEPROP 3 LASTPIN (-525 475) SIG_NAME GND\g
J 0
(-515 485);
DISPLAY 0.659574 (-515 485);
PAINT MONO (-515 485);
DISPLAY INVISIBLE (-515 485);
FORCEPROP 1 LAST PATH I52
J 0
(-450 425);
DISPLAY 0.872340 (-450 425);
PAINT AQUA (-450 425);
DISPLAY INVISIBLE (-450 425);
FORCEPROP 1 LAST HDL_POWER GND
J 1
(-500 350);
DISPLAY 0.702128 (-500 350);
PAINT GREEN (-500 350);
DISPLAY INVISIBLE (-500 350);
FORCEPROP 2 LAST CDS_LIB logical_power
J 0
(-525 425);
DISPLAY INVISIBLE (-525 425);
FORCEADD OFFPAGE..5
R 2
(1175 825);
FORCEPROP 2 LAST $XR1 36 
J 0
(1454 825);
DISPLAY 0.638298 (1454 825);
PAINT MONO (1454 825);
FORCEPROP 2 LAST $XR0 22 
J 0
(1364 825);
DISPLAY 0.638298 (1364 825);
PAINT MONO (1364 825);
FORCEPROP 2 LAST PATH I53
J 0
(1475 875);
DISPLAY 0.680851 (1475 875);
DISPLAY INVISIBLE (1475 875);
FORCEPROP 1 LAST COMMENT_BODY TRUE
J 2
(1075 750);
DISPLAY 0.872340 (1075 750);
PAINT PEACH (1075 750);
DISPLAY INVISIBLE (1075 750);
FORCEPROP 1 LAST OFFPAGE TRUE
J 2
(850 700);
DISPLAY 0.872340 (850 700);
PAINT GREEN (850 700);
DISPLAY INVISIBLE (850 700);
FORCEPROP 2 LAST CDS_LIB standard
J 0
(1175 825);
DISPLAY INVISIBLE (1175 825);
FORCEADD Q_RES..1
(-100 825);
FORCEPROP 1 LAST PACK_TYPE 0402LF
J 0
(-175 775);
DISPLAY 0.510638 (-175 775);
PAINT SKYBLUE (-175 775);
FORCEPROP 1 LAST MATERIAL CHIP
J 0
(150 825);
DISPLAY 0.510638 (150 825);
PAINT RED (150 825);
FORCEPROP 1 LAST VALUE 0
J 2
(125 825);
DISPLAY 0.510638 (125 825);
PAINT SKYBLUE (125 825);
FORCEPROP 1 LAST PART_NUMBER CS00002JB13
J 0
(-200 875);
DISPLAY 0.510638 (-200 875);
PAINT WHITE (-200 875);
FORCEPROP 1 LAST WATTAGE 1/16W
J 2
(-125 675);
DISPLAY 0.510638 (-125 675);
PAINT SKYBLUE (-125 675);
DISPLAY INVISIBLE (-125 675);
FORCEPROP 1 LAST PATH I54
J 0
(-150 975);
DISPLAY 0.978723 (-150 975);
PAINT WHITE (-150 975);
DISPLAY INVISIBLE (-150 975);
FORCEPROP 1 LAST TOLERANCE 5%
J 0
(-100 725);
DISPLAY 0.510638 (-100 725);
PAINT SKYBLUE (-100 725);
DISPLAY INVISIBLE (-100 725);
FORCEPROP 2 LAST CDS_LIB pure_quanta
J 0
(-100 825);
DISPLAY INVISIBLE (-100 825);
FORCEPROP 1 LAST LOCATION R277
J 0
(-350 825);
DISPLAY 0.702128 (-350 825);
PAINT YELLOW (-350 825);
FORCEPROP 1 LASTPIN (-200 825) $PN 1
J 0
(-188 837);
DISPLAY 0.808511 (-188 837);
PAINT WHITE (-188 837);
FORCEPROP 1 LASTPIN (0 825) $PN 2
J 0
(-38 837);
DISPLAY 0.808511 (-38 837);
PAINT WHITE (-38 837);
FORCEPROP 2 LAST $SEC 1
J 0
(-225 1050);
DISPLAY 0.680851 (-225 1050);
PAINT MONO (-225 1050);
DISPLAY INVISIBLE (-225 1050);
FORCEPROP 0 LAST CDS_SEC 1
J 0
(-225 1050);
DISPLAY 0.680851 (-225 1050);
PAINT MONO (-225 1050);
DISPLAY INVISIBLE (-225 1050);
FORCEADD Q_RES..1
(-3650 325);
FORCEPROP 1 LAST TOLERANCE 5%
J 0
(-4050 250);
DISPLAY 0.978723 (-4050 250);
FORCEPROP 1 LAST PACK_TYPE 0402LF
J 0
(-3700 250);
DISPLAY 0.978723 (-3700 250);
FORCEPROP 1 LAST WATTAGE 1/16W
J 2
(-3725 250);
DISPLAY 0.978723 (-3725 250);
FORCEPROP 1 LAST MATERIAL CHIP
J 0
(-3900 375);
DISPLAY 0.978723 (-3900 375);
FORCEPROP 1 LAST VALUE 0
J 2
(-3800 325);
DISPLAY 0.978723 (-3800 325);
FORCEPROP 1 LAST PART_NUMBER CS00002JB13
J 0
(-3875 425);
DISPLAY 0.978723 (-3875 425);
FORCEPROP 1 LAST PATH I55
J 0
(-3700 475);
DISPLAY 0.978723 (-3700 475);
PAINT WHITE (-3700 475);
DISPLAY INVISIBLE (-3700 475);
FORCEPROP 2 LAST CDS_LIB pure_quanta
J 0
(-3650 325);
DISPLAY INVISIBLE (-3650 325);
FORCEPROP 1 LAST LOCATION R399
J 0
(-3700 375);
DISPLAY 0.978723 (-3700 375);
FORCEPROP 1 LASTPIN (-3750 325) $PN 1
J 0
(-3738 337);
DISPLAY 0.787234 (-3738 337);
PAINT MONO (-3738 337);
FORCEPROP 1 LASTPIN (-3550 325) $PN 2
J 0
(-3588 337);
DISPLAY 0.787234 (-3588 337);
PAINT MONO (-3588 337);
FORCEPROP 0 LAST $SEC 1
J 0
(-3700 475);
DISPLAY 0.680851 (-3700 475);
PAINT MONO (-3700 475);
DISPLAY INVISIBLE (-3700 475);
FORCEPROP 0 LAST CDS_SEC 1
J 0
(-3700 475);
DISPLAY 0.680851 (-3700 475);
DISPLAY INVISIBLE (-3700 475);
FORCEADD OFFPAGE..4
R 2
(-4825 325);
FORCEPROP 2 LAST $XR0 56 
J 0
(-5076 325);
DISPLAY 0.638298 (-5076 325);
PAINT MONO (-5076 325);
FORCEPROP 2 LAST PATH I56
J 0
(-5025 375);
DISPLAY 0.680851 (-5025 375);
DISPLAY INVISIBLE (-5025 375);
FORCEPROP 1 LAST COMMENT_BODY TRUE
J 2
(-4800 225);
DISPLAY 0.872340 (-4800 225);
PAINT PEACH (-4800 225);
DISPLAY INVISIBLE (-4800 225);
FORCEPROP 1 LAST OFFPAGE TRUE
J 2
(-5150 200);
DISPLAY 0.872340 (-5150 200);
PAINT GREEN (-5150 200);
DISPLAY INVISIBLE (-5150 200);
FORCEPROP 2 LAST CDS_LIB standard
J 0
(-4825 325);
DISPLAY INVISIBLE (-4825 325);
FORCEADD UNIVERSAL_GND..1
(-5225 925);
FORCEPROP 3 LASTPIN (-5225 975) SIG_NAME GND\g
J 0
(-5215 985);
DISPLAY 0.659574 (-5215 985);
PAINT MONO (-5215 985);
DISPLAY INVISIBLE (-5215 985);
FORCEPROP 2 LAST CDS_LIB logical_power
J 0
(-5225 925);
DISPLAY INVISIBLE (-5225 925);
FORCEPROP 1 LAST PATH I57
J 0
(-5150 925);
DISPLAY 0.872340 (-5150 925);
PAINT AQUA (-5150 925);
DISPLAY INVISIBLE (-5150 925);
FORCEPROP 1 LAST HDL_POWER GND
J 1
(-5200 850);
DISPLAY 0.702128 (-5200 850);
PAINT GREEN (-5200 850);
DISPLAY INVISIBLE (-5200 850);
FORCEADD Q_CAP..1
(-5225 1125);
FORCEPROP 1 LAST PACK_TYPE 0402
J 0
(-5175 925);
DISPLAY 0.510638 (-5175 925);
PAINT SKYBLUE (-5175 925);
FORCEPROP 1 LAST TOLERANCE 10%
J 0
(-5175 1075);
DISPLAY 0.510638 (-5175 1075);
PAINT SKYBLUE (-5175 1075);
FORCEPROP 1 LAST VALUE 0.1UF
J 0
(-5175 1175);
DISPLAY 0.510638 (-5175 1175);
PAINT SKYBLUE (-5175 1175);
FORCEPROP 1 LAST PART_NUMBER CH4104K1B00
J 0
(-5175 975);
DISPLAY 0.510638 (-5175 975);
PAINT WHITE (-5175 975);
FORCEPROP 1 LAST MATERIAL X7R
J 0
(-5175 1025);
DISPLAY 0.510638 (-5175 1025);
PAINT SKYBLUE (-5175 1025);
FORCEPROP 1 LAST VOLTAGE 25V
J 0
(-5175 1125);
DISPLAY 0.510638 (-5175 1125);
PAINT SKYBLUE (-5175 1125);
FORCEPROP 2 LAST CDS_LIB pure_quanta
J 0
(-5225 1125);
DISPLAY INVISIBLE (-5225 1125);
FORCEPROP 1 LAST PATH I58
J 0
(-5175 1275);
DISPLAY 0.978723 (-5175 1275);
PAINT WHITE (-5175 1275);
DISPLAY INVISIBLE (-5175 1275);
FORCEPROP 1 LAST $LOCATION C280
J 0
(-5175 1225);
DISPLAY 0.978723 (-5175 1225);
FORCEPROP 1 LASTPIN (-5225 1225) $PN 1
J 0
(-5215 1205);
DISPLAY 0.787234 (-5215 1205);
PAINT MONO (-5215 1205);
FORCEPROP 1 LASTPIN (-5225 1025) $PN 2
J 0
(-5215 1005);
DISPLAY 0.787234 (-5215 1005);
PAINT MONO (-5215 1005);
FORCEPROP 0 LAST CDS_LOCATION C280
J 0
(-5175 1275);
DISPLAY 0.680851 (-5175 1275);
DISPLAY INVISIBLE (-5175 1275);
FORCEPROP 0 LAST $SEC 1
J 0
(-5175 1275);
DISPLAY 0.680851 (-5175 1275);
PAINT MONO (-5175 1275);
DISPLAY INVISIBLE (-5175 1275);
FORCEPROP 0 LAST CDS_SEC 1
J 0
(-5175 1275);
DISPLAY 0.680851 (-5175 1275);
DISPLAY INVISIBLE (-5175 1275);
FORCEADD OFFPAGE..4
R 2
(-4775 2825);
FORCEPROP 2 LAST $XR2 52 
J 0
(-5176 2825);
DISPLAY 0.638298 (-5176 2825);
PAINT MONO (-5176 2825);
FORCEPROP 2 LAST $XR3 54 
J 0
(-5266 2825);
DISPLAY 0.638298 (-5266 2825);
PAINT MONO (-5266 2825);
FORCEPROP 2 LAST $XR4 55 
J 0
(-5356 2825);
DISPLAY 0.638298 (-5356 2825);
PAINT MONO (-5356 2825);
FORCEPROP 2 LAST $XR0 51 
J 0
(-4996 2825);
DISPLAY 0.638298 (-4996 2825);
PAINT MONO (-4996 2825);
FORCEPROP 2 LAST $XR1 35 
J 0
(-5086 2825);
DISPLAY 0.638298 (-5086 2825);
PAINT MONO (-5086 2825);
FORCEPROP 1 LAST COMMENT_BODY TRUE
J 2
(-4750 2725);
DISPLAY 0.872340 (-4750 2725);
PAINT PEACH (-4750 2725);
DISPLAY INVISIBLE (-4750 2725);
FORCEPROP 1 LAST OFFPAGE TRUE
J 2
(-5100 2700);
DISPLAY 0.872340 (-5100 2700);
PAINT GREEN (-5100 2700);
DISPLAY INVISIBLE (-5100 2700);
FORCEPROP 2 LAST CDS_LIB standard
J 0
(-4775 2825);
DISPLAY INVISIBLE (-4775 2825);
FORCEPROP 2 LAST PATH I59
J 0
(-5025 2875);
DISPLAY 0.680851 (-5025 2875);
DISPLAY INVISIBLE (-5025 2875);
FORCEADD OFFPAGE..4
R 2
(-4775 2725);
FORCEPROP 2 LAST $XR0 55 
J 0
(-4996 2725);
DISPLAY 0.638298 (-4996 2725);
PAINT MONO (-4996 2725);
FORCEPROP 2 LAST $XR1 36 
J 0
(-5086 2725);
DISPLAY 0.638298 (-5086 2725);
PAINT MONO (-5086 2725);
FORCEPROP 1 LAST COMMENT_BODY TRUE
J 2
(-4750 2625);
DISPLAY 0.872340 (-4750 2625);
PAINT PEACH (-4750 2625);
DISPLAY INVISIBLE (-4750 2625);
FORCEPROP 1 LAST OFFPAGE TRUE
J 2
(-5100 2600);
DISPLAY 0.872340 (-5100 2600);
PAINT GREEN (-5100 2600);
DISPLAY INVISIBLE (-5100 2600);
FORCEPROP 2 LAST CDS_LIB standard
J 0
(-4775 2725);
DISPLAY INVISIBLE (-4775 2725);
FORCEPROP 2 LAST PATH I60
J 0
(-5025 2775);
DISPLAY 0.680851 (-5025 2775);
DISPLAY INVISIBLE (-5025 2775);
FORCEADD UNIVERSAL_GND..1
(-3800 2350);
FORCEPROP 3 LASTPIN (-3800 2400) SIG_NAME GND\g
J 0
(-3790 2410);
DISPLAY 0.659574 (-3790 2410);
PAINT MONO (-3790 2410);
DISPLAY INVISIBLE (-3790 2410);
FORCEPROP 1 LAST PATH I61
J 0
(-3725 2350);
DISPLAY 0.872340 (-3725 2350);
PAINT AQUA (-3725 2350);
DISPLAY INVISIBLE (-3725 2350);
FORCEPROP 2 LAST CDS_LIB logical_power
J 0
(-3800 2350);
DISPLAY INVISIBLE (-3800 2350);
FORCEPROP 1 LAST HDL_POWER GND
J 1
(-3775 2275);
DISPLAY 0.702128 (-3775 2275);
PAINT GREEN (-3775 2275);
DISPLAY INVISIBLE (-3775 2275);
FORCEADD UNIVERSAL_GND..1
(-3450 3050);
FORCEPROP 3 LASTPIN (-3450 3100) SIG_NAME GND\g
J 0
(-3440 3110);
DISPLAY 0.659574 (-3440 3110);
PAINT MONO (-3440 3110);
DISPLAY INVISIBLE (-3440 3110);
FORCEPROP 1 LAST PATH I63
J 0
(-3375 3050);
DISPLAY 0.872340 (-3375 3050);
PAINT AQUA (-3375 3050);
DISPLAY INVISIBLE (-3375 3050);
FORCEPROP 1 LAST HDL_POWER GND
J 1
(-3425 2975);
DISPLAY 0.702128 (-3425 2975);
PAINT GREEN (-3425 2975);
DISPLAY INVISIBLE (-3425 2975);
FORCEPROP 2 LAST CDS_LIB logical_power
J 0
(-3450 3050);
DISPLAY INVISIBLE (-3450 3050);
FORCEADD Q_CAP..1
R 2
(-3450 3250);
FORCEPROP 1 LAST MATERIAL X7R
J 2
(-3500 3125);
DISPLAY 0.510638 (-3500 3125);
PAINT SKYBLUE (-3500 3125);
FORCEPROP 1 LAST PACK_TYPE 0402
J 2
(-3500 3075);
DISPLAY 0.510638 (-3500 3075);
PAINT SKYBLUE (-3500 3075);
FORCEPROP 1 LAST VALUE 0.1UF
J 2
(-3500 3275);
DISPLAY 0.510638 (-3500 3275);
PAINT SKYBLUE (-3500 3275);
FORCEPROP 1 LAST PART_NUMBER CH4104K1B00
J 2
(-3500 3025);
DISPLAY 0.510638 (-3500 3025);
PAINT WHITE (-3500 3025);
FORCEPROP 1 LAST TOLERANCE 10%
J 2
(-3500 3175);
DISPLAY 0.510638 (-3500 3175);
PAINT SKYBLUE (-3500 3175);
FORCEPROP 1 LAST VOLTAGE 25V
J 2
(-3500 3225);
DISPLAY 0.510638 (-3500 3225);
PAINT SKYBLUE (-3500 3225);
FORCEPROP 1 LAST PATH I64
J 2
(-3500 3400);
DISPLAY 0.978723 (-3500 3400);
PAINT WHITE (-3500 3400);
DISPLAY INVISIBLE (-3500 3400);
FORCEPROP 2 LAST CDS_LIB pure_quanta
J 0
(-3450 3250);
DISPLAY INVISIBLE (-3450 3250);
FORCEPROP 1 LAST $LOCATION C302
J 2
(-3500 3350);
DISPLAY 0.978723 (-3500 3350);
FORCEPROP 1 LASTPIN (-3450 3350) $PN 1
J 2
(-3460 3330);
DISPLAY 0.787234 (-3460 3330);
PAINT MONO (-3460 3330);
FORCEPROP 1 LASTPIN (-3450 3150) $PN 2
J 2
(-3460 3130);
DISPLAY 0.787234 (-3460 3130);
PAINT MONO (-3460 3130);
FORCEPROP 0 LAST CDS_LOCATION C302
J 0
(-3500 3400);
DISPLAY 0.680851 (-3500 3400);
DISPLAY INVISIBLE (-3500 3400);
FORCEPROP 0 LAST $SEC 1
J 0
(-3500 3400);
DISPLAY 0.680851 (-3500 3400);
PAINT MONO (-3500 3400);
DISPLAY INVISIBLE (-3500 3400);
FORCEPROP 0 LAST CDS_SEC 1
J 0
(-3500 3400);
DISPLAY 0.680851 (-3500 3400);
DISPLAY INVISIBLE (-3500 3400);
FORCEADD 74LVC1G08GW..1
(-3750 2775);
FORCEPROP 2 LAST PACK_TYPE SM
J 0
(-3600 2725);
DISPLAY 0.680851 (-3600 2725);
FORCEPROP 2 LAST VALUE 74LVC1G08GW
J 0
(-3700 2900);
DISPLAY 0.680851 (-3700 2900);
FORCEPROP 1 LAST PART_NUMBER ALVC1G08009
J 0
(-3600 2635);
DISPLAY 0.723404 (-3600 2635);
PAINT GREEN (-3600 2635);
FORCEPROP 1 LAST MATERIAL IC
J 0
(-3600 2585);
DISPLAY 0.723404 (-3600 2585);
PAINT GREEN (-3600 2585);
FORCEPROP 1 LAST PATH I66
J 0
(-3475 2580);
DISPLAY 0.723404 (-3475 2580);
PAINT GREEN (-3475 2580);
DISPLAY INVISIBLE (-3475 2580);
FORCEPROP 1 LAST NEEDS_NO_SIZE TRUE
J 0
(-3750 2775);
DISPLAY 0.468085 (-3750 2775);
PAINT GREEN (-3750 2775);
DISPLAY INVISIBLE (-3750 2775);
FORCEPROP 2 LAST CDS_LIB pure_quanta
J 0
(-3750 2775);
DISPLAY INVISIBLE (-3750 2775);
FORCEPROP 1 LAST $LOCATION U53
J 0
(-3600 2680);
DISPLAY 0.723404 (-3600 2680);
PAINT GREEN (-3600 2680);
FORCEPROP 0 LASTPIN (-4050 2725) $PN 2
J 2
(-4060 2735);
DISPLAY 0.680851 (-4060 2735);
PAINT MONO (-4060 2735);
FORCEPROP 0 LASTPIN (-4050 2825) $PN 1
J 2
(-4060 2835);
DISPLAY 0.680851 (-4060 2835);
PAINT MONO (-4060 2835);
FORCEPROP 0 LASTPIN (-3800 2525) $PN 3
R 1
J 2
(-3810 2515);
DISPLAY 0.680851 (-3810 2515);
PAINT MONO (-3810 2515);
FORCEPROP 0 LASTPIN (-3800 3025) $PN 5
R 1
J 0
(-3810 3035);
DISPLAY 0.680851 (-3810 3035);
PAINT MONO (-3810 3035);
FORCEPROP 0 LASTPIN (-3450 2775) $PN 4
J 0
(-3440 2785);
DISPLAY 0.680851 (-3440 2785);
PAINT MONO (-3440 2785);
FORCEPROP 0 LAST CDS_LOCATION U53
J 0
(-3700 2950);
DISPLAY 0.680851 (-3700 2950);
DISPLAY INVISIBLE (-3700 2950);
FORCEPROP 0 LAST $SEC 1
J 0
(-3700 2950);
DISPLAY 0.680851 (-3700 2950);
PAINT MONO (-3700 2950);
DISPLAY INVISIBLE (-3700 2950);
FORCEPROP 0 LAST CDS_SEC 1
J 0
(-3700 2950);
DISPLAY 0.680851 (-3700 2950);
DISPLAY INVISIBLE (-3700 2950);
FORCEADD Q_CAP..1
(-4025 -500);
FORCEPROP 1 LAST MATERIAL X6S
J 0
(-3975 -600);
DISPLAY 0.510638 (-3975 -600);
PAINT SKYBLUE (-3975 -600);
FORCEPROP 1 LAST VALUE 1UF
J 0
(-3975 -450);
DISPLAY 0.510638 (-3975 -450);
PAINT SKYBLUE (-3975 -450);
FORCEPROP 1 LAST TOLERANCE 10%
J 0
(-3975 -550);
DISPLAY 0.510638 (-3975 -550);
PAINT SKYBLUE (-3975 -550);
FORCEPROP 1 LAST VOLTAGE 25V
J 0
(-3975 -500);
DISPLAY 0.510638 (-3975 -500);
PAINT SKYBLUE (-3975 -500);
FORCEPROP 1 LAST PACK_TYPE C0402
J 0
(-3975 -700);
DISPLAY 0.510638 (-3975 -700);
PAINT SKYBLUE (-3975 -700);
FORCEPROP 1 LAST PART_NUMBER CH5104KEB02
J 0
(-3975 -650);
DISPLAY 0.510638 (-3975 -650);
PAINT WHITE (-3975 -650);
FORCEPROP 1 LAST PATH I7
J 0
(-3975 -350);
DISPLAY 0.978723 (-3975 -350);
PAINT WHITE (-3975 -350);
DISPLAY INVISIBLE (-3975 -350);
FORCEPROP 2 LAST CDS_LIB pure_quanta
J 0
(-4025 -500);
DISPLAY INVISIBLE (-4025 -500);
FORCEPROP 2 LAST SEC_TYPE C0402
J 0
(-3975 -300);
DISPLAY 1.021277 (-3975 -300);
DISPLAY INVISIBLE (-3975 -300);
FORCEPROP 1 LAST LOCATION PC260
J 0
(-3975 -400);
DISPLAY 0.702128 (-3975 -400);
PAINT AQUA (-3975 -400);
FORCEPROP 1 LASTPIN (-4025 -400) $PN 1
J 0
(-4015 -420);
DISPLAY 0.808511 (-4015 -420);
PAINT WHITE (-4015 -420);
FORCEPROP 1 LASTPIN (-4025 -600) $PN 2
J 0
(-4015 -620);
DISPLAY 0.808511 (-4015 -620);
PAINT WHITE (-4015 -620);
FORCEPROP 2 LAST SEC 1
J 0
(-3975 -300);
DISPLAY 0.680851 (-3975 -300);
PAINT MONO (-3975 -300);
DISPLAY INVISIBLE (-3975 -300);
FORCEADD OFFPAGE..5
R 2
(-2400 2775);
FORCEPROP 2 LAST $XR0 56 
J 0
(-2211 2775);
DISPLAY 0.638298 (-2211 2775);
PAINT MONO (-2211 2775);
FORCEPROP 2 LAST PATH I70
J 0
(-2200 2825);
DISPLAY 0.680851 (-2200 2825);
DISPLAY INVISIBLE (-2200 2825);
FORCEPROP 1 LAST COMMENT_BODY TRUE
J 2
(-2500 2700);
DISPLAY 0.872340 (-2500 2700);
PAINT PEACH (-2500 2700);
DISPLAY INVISIBLE (-2500 2700);
FORCEPROP 1 LAST OFFPAGE TRUE
J 2
(-2725 2650);
DISPLAY 0.872340 (-2725 2650);
PAINT GREEN (-2725 2650);
DISPLAY INVISIBLE (-2725 2650);
FORCEPROP 2 LAST CDS_LIB standard
J 0
(-2400 2775);
DISPLAY INVISIBLE (-2400 2775);
FORCEADD Q_RES..2
(-2950 -850);
FORCEPROP 1 LAST VALUE 100K
J 0
(-2905 -775);
DISPLAY 0.510638 (-2905 -775);
PAINT SKYBLUE (-2905 -775);
FORCEPROP 1 LAST TOLERANCE 1%
J 0
(-2905 -825);
DISPLAY 0.510638 (-2905 -825);
PAINT SKYBLUE (-2905 -825);
FORCEPROP 1 LAST WATTAGE 1/16W
J 0
(-2910 -875);
DISPLAY 0.510638 (-2910 -875);
PAINT SKYBLUE (-2910 -875);
FORCEPROP 1 LAST PACK_TYPE 0402LF
J 0
(-2910 -1025);
DISPLAY 0.510638 (-2910 -1025);
PAINT SKYBLUE (-2910 -1025);
FORCEPROP 1 LAST MATERIAL CHIP
J 0
(-2910 -925);
DISPLAY 0.510638 (-2910 -925);
PAINT SKYBLUE (-2910 -925);
FORCEPROP 1 LAST PART_NUMBER CS41002FB09
J 0
(-2910 -975);
DISPLAY 0.510638 (-2910 -975);
PAINT WHITE (-2910 -975);
FORCEPROP 2 LAST CDS_LIB pure_quanta
J 0
(-2950 -850);
DISPLAY INVISIBLE (-2950 -850);
FORCEPROP 1 LAST PATH I71
J 0
(-2900 -675);
DISPLAY 0.978723 (-2900 -675);
PAINT WHITE (-2900 -675);
DISPLAY INVISIBLE (-2900 -675);
FORCEPROP 1 LAST LOCATION PR543
J 0
(-2905 -725);
DISPLAY 0.702128 (-2905 -725);
PAINT AQUA (-2905 -725);
FORCEPROP 1 LASTPIN (-2950 -750) $PN 1
J 0
(-2945 -788);
DISPLAY 0.787234 (-2945 -788);
PAINT MONO (-2945 -788);
FORCEPROP 1 LASTPIN (-2950 -950) $PN 2
J 0
(-2945 -940);
DISPLAY 0.787234 (-2945 -940);
PAINT MONO (-2945 -940);
FORCEPROP 0 LAST $SEC 1
J 0
(-2900 -675);
DISPLAY 0.680851 (-2900 -675);
PAINT MONO (-2900 -675);
DISPLAY INVISIBLE (-2900 -675);
FORCEPROP 0 LAST CDS_SEC 1
J 0
(-2900 -675);
DISPLAY 0.680851 (-2900 -675);
DISPLAY INVISIBLE (-2900 -675);
FORCEADD Q_RES..1
(-3650 550);
FORCEPROP 1 LAST MATERIAL EMPTY
J 0
(-3900 600);
DISPLAY 0.978723 (-3900 600);
FORCEPROP 1 LAST PART_NUMBER CS00002JB13
J 0
(-3875 650);
DISPLAY 0.978723 (-3875 650);
FORCEPROP 1 LAST TOLERANCE 5%
J 0
(-4050 475);
DISPLAY 0.978723 (-4050 475);
FORCEPROP 1 LAST VALUE 0
J 2
(-3800 550);
DISPLAY 0.978723 (-3800 550);
FORCEPROP 1 LAST WATTAGE 1/16W
J 2
(-3725 475);
DISPLAY 0.978723 (-3725 475);
FORCEPROP 1 LAST PACK_TYPE 0402LF
J 0
(-3700 475);
DISPLAY 0.978723 (-3700 475);
FORCEPROP 1 LAST PATH I72
J 0
(-3700 700);
DISPLAY 0.978723 (-3700 700);
PAINT WHITE (-3700 700);
DISPLAY INVISIBLE (-3700 700);
FORCEPROP 2 LAST CDS_LIB pure_quanta
J 0
(-3650 550);
DISPLAY INVISIBLE (-3650 550);
FORCEPROP 1 LAST $LOCATION R878
J 0
(-3650 600);
DISPLAY 0.978723 (-3650 600);
FORCEPROP 1 LASTPIN (-3750 550) $PN 1
J 0
(-3738 562);
DISPLAY 0.787234 (-3738 562);
PAINT MONO (-3738 562);
FORCEPROP 1 LASTPIN (-3550 550) $PN 2
J 0
(-3588 562);
DISPLAY 0.787234 (-3588 562);
PAINT MONO (-3588 562);
FORCEPROP 0 LAST CDS_LOCATION R878
J 0
(-3875 700);
DISPLAY 0.680851 (-3875 700);
DISPLAY INVISIBLE (-3875 700);
FORCEPROP 0 LAST $SEC 1
J 0
(-3875 700);
DISPLAY 0.680851 (-3875 700);
PAINT MONO (-3875 700);
DISPLAY INVISIBLE (-3875 700);
FORCEPROP 0 LAST CDS_SEC 1
J 0
(-3875 700);
DISPLAY 0.680851 (-3875 700);
DISPLAY INVISIBLE (-3875 700);
FORCEADD OFFPAGE..4
R 2
(-4825 550);
FORCEPROP 2 LAST $XR0 55 
J 0
(-5076 550);
DISPLAY 0.638298 (-5076 550);
PAINT MONO (-5076 550);
FORCEPROP 2 LAST CDS_LIB standard
J 0
(-4825 550);
DISPLAY INVISIBLE (-4825 550);
FORCEPROP 1 LAST OFFPAGE TRUE
J 2
(-5150 425);
DISPLAY 0.872340 (-5150 425);
PAINT GREEN (-5150 425);
DISPLAY INVISIBLE (-5150 425);
FORCEPROP 1 LAST COMMENT_BODY TRUE
J 2
(-4800 450);
DISPLAY 0.872340 (-4800 450);
PAINT PEACH (-4800 450);
DISPLAY INVISIBLE (-4800 450);
FORCEPROP 2 LAST PATH I73
J 0
(-5075 600);
DISPLAY 0.680851 (-5075 600);
DISPLAY INVISIBLE (-5075 600);
FORCEADD UNIVERSAL_POWER..1
(-3450 3450);
FORCEPROP 3 LASTPIN (-3450 3400) SIG_NAME P3V3_LDO\g
J 0
(-3440 3410);
DISPLAY 0.659574 (-3440 3410);
PAINT MONO (-3440 3410);
DISPLAY INVISIBLE (-3440 3410);
FORCEPROP 1 LAST HDL_POWER P3V3_LDO
J 1
(-3450 3500);
DISPLAY 0.702128 (-3450 3500);
PAINT GREEN (-3450 3500);
FORCEPROP 1 LAST PATH I74
J 0
(-3400 3475);
DISPLAY 0.872340 (-3400 3475);
PAINT AQUA (-3400 3475);
DISPLAY INVISIBLE (-3400 3475);
FORCEPROP 2 LAST CDS_LIB logical_power
J 0
(-3450 3450);
DISPLAY INVISIBLE (-3450 3450);
FORCEADD Q_RES..2
(-4025 -75);
FORCEPROP 1 LAST PART_NUMBER CS-5102JB02
J 0
(-3985 -200);
DISPLAY 0.510638 (-3985 -200);
PAINT WHITE (-3985 -200);
FORCEPROP 1 LAST PACK_TYPE 0402LF
J 0
(-3985 -250);
DISPLAY 0.510638 (-3985 -250);
PAINT SKYBLUE (-3985 -250);
FORCEPROP 1 LAST MATERIAL CHIP
J 0
(-3985 -150);
DISPLAY 0.510638 (-3985 -150);
PAINT SKYBLUE (-3985 -150);
FORCEPROP 1 LAST WATTAGE 1/16W
J 0
(-3985 -100);
DISPLAY 0.510638 (-3985 -100);
PAINT SKYBLUE (-3985 -100);
FORCEPROP 1 LAST TOLERANCE 5%
J 0
(-3980 -50);
DISPLAY 0.510638 (-3980 -50);
PAINT SKYBLUE (-3980 -50);
FORCEPROP 1 LAST VALUE 5.1
J 0
(-3980 0);
DISPLAY 0.510638 (-3980 0);
PAINT SKYBLUE (-3980 0);
FORCEPROP 1 LAST PATH I8
J 0
(-3975 100);
DISPLAY 0.978723 (-3975 100);
PAINT WHITE (-3975 100);
DISPLAY INVISIBLE (-3975 100);
FORCEPROP 2 LAST CDS_LIB pure_quanta
J 0
(-4025 -75);
DISPLAY INVISIBLE (-4025 -75);
FORCEPROP 1 LAST LOCATION PR541
J 0
(-3980 50);
DISPLAY 0.702128 (-3980 50);
PAINT AQUA (-3980 50);
FORCEPROP 0 LAST $SEC 1
J 0
(-3975 100);
DISPLAY 0.680851 (-3975 100);
PAINT MONO (-3975 100);
DISPLAY INVISIBLE (-3975 100);
FORCEPROP 0 LAST CDS_SEC 1
J 0
(-3975 100);
DISPLAY 1.021277 (-3975 100);
DISPLAY INVISIBLE (-3975 100);
FORCEPROP 1 LASTPIN (-4025 25) $PN 1
J 0
(-4020 -13);
DISPLAY 0.808511 (-4020 -13);
PAINT WHITE (-4020 -13);
DISPLAY INVISIBLE (-4020 -13);
FORCEPROP 1 LASTPIN (-4025 -175) $PN 2
J 0
(-4020 -165);
DISPLAY 0.808511 (-4020 -165);
PAINT WHITE (-4020 -165);
DISPLAY INVISIBLE (-4020 -165);
FORCEADD VCCAUX15..1
(-4025 150);
FORCEPROP 3 LASTPIN (-4025 100) SIG_NAME PVCC2_AUX\g
J 0
(-4015 110);
DISPLAY 0.659574 (-4015 110);
PAINT MONO (-4015 110);
DISPLAY INVISIBLE (-4015 110);
FORCEPROP 1 LAST HDL_POWER PVCC2_AUX
J 1
(-4025 200);
DISPLAY 0.702128 (-4025 200);
PAINT GREEN (-4025 200);
FORCEPROP 1 LAST PATH I9
J 0
(-3975 175);
DISPLAY 0.872340 (-3975 175);
PAINT AQUA (-3975 175);
DISPLAY INVISIBLE (-3975 175);
FORCEPROP 2 LAST CDS_LIB logical_power
J 0
(-4025 150);
DISPLAY INVISIBLE (-4025 150);
FORCEADD QUANTA_TITLE_BLOCK_C..1
(3450 -2425);
FORCEPROP 0 LAST CDS_CON_LAST_MODIFIED Fri Aug 25 17:25:49 2023
J 0
(1565 -2410);
DISPLAY INVISIBLE (1565 -2410);
FORCEPROP 2 LAST Q_DEPT 
J 1
(-313 -2376);
DISPLAY 1.957447 (-313 -2376);
PAINT GREEN (-313 -2376);
FORCEPROP 1 LAST CUSTOM_TXT_CDS <CON_LAST_MODIFIED>
J 0
(1565 -2410);
DISPLAY 0.978723 (1565 -2410);
FORCEPROP 2 LAST CUSTOM_TXT_CDS <XR_PAGE_TITLE>
J 0
(-4440 2825);
DISPLAY 0.638298 (-4440 2825);
PAINT PINK (-4440 2825);
DISPLAY INVISIBLE (-4440 2825);
FORCEPROP 1 LAST CUSTOM_TXT_CDS <NAME_2>
J 0
(275 -2375);
FORCEPROP 1 LAST CUSTOM_TXT_CDS <NAME_1>
J 0
(275 -2250);
FORCEPROP 1 LAST CUSTOM_TXT_CDS <Q_NUMBER>
J 0
(2047 -2322);
DISPLAY 1.212766 (2047 -2322);
FORCEPROP 1 LAST CUSTOM_TXT_CDS <Q_PROJ>
J 0
(1068 -2323);
DISPLAY 1.212766 (1068 -2323);
FORCEPROP 1 LAST CUSTOM_TXT_CDS <Q_REV>
J 0
(3266 -2322);
DISPLAY 1.212766 (3266 -2322);
FORCEPROP 1 LAST CUSTOM_TXT_CDS <CON_PAGE_NUM> OF <CON_TOTAL_PAGES>
J 0
(3004 -2407);
DISPLAY 0.978723 (3004 -2407);
FORCEPROP 1 LAST Q_TITLE NB695 - P1V0_AUX
J 0
(-5916 -2399);
DISPLAY 2.446809 (-5916 -2399);
PAINT GREEN (-5916 -2399);
FORCEPROP 1 LAST COMMENT_BODY TRUE
J 0
(3462 -2438);
DISPLAY 0.978723 (3462 -2438);
PAINT PEACH (3462 -2438);
DISPLAY INVISIBLE (3462 -2438);
FORCEPROP 2 LAST PAGE_BORDER TRUE
J 0
(-4440 2825);
DISPLAY 0.638298 (-4440 2825);
PAINT PINK (-4440 2825);
DISPLAY INVISIBLE (-4440 2825);
FORCEPROP 1 LAST CDS_LMAN_SYM_OUTLINE -9475,6775,100,-125
J 0
(3450 -2425);
DISPLAY 0.468085 (3450 -2425);
PAINT GREEN (3450 -2425);
DISPLAY INVISIBLE (3450 -2425);
FORCEPROP 2 LAST CDS_LIB pure_quanta
J 0
(3450 -2425);
DISPLAY INVISIBLE (3450 -2425);
FORCEPROP 2 LAST CDS_XR_PAGE_TITLE CR-56 : @SCM_LIB.SCM(SCH_1):PAGE56
J 0
(-4440 2825);
DISPLAY 0.638298 (-4440 2825);
PAINT PINK (-4440 2825);
DISPLAY INVISIBLE (-4440 2825);
FORCEADD CAD_NOTE..1
(-675 1175);
FORCEPROP 0 LAST L1 THE CAP & DAMPING RS FOR PWRGD SHOULD CLOSE TO DRIVE-END
J 0
(-725 975);
DISPLAY 1.021277 (-725 975);
PAINT WHITE (-725 975);
FORCEPROP 1 LAST COMMENT_BODY TRUE
J 0
(-650 1275);
DISPLAY 0.978723 (-650 1275);
PAINT PEACH (-650 1275);
DISPLAY INVISIBLE (-650 1275);
FORCEPROP 2 LAST CDS_LIB logical_power
J 0
(-675 1175);
DISPLAY INVISIBLE (-675 1175);
FORCEADD DNS..2
(-3100 -1825);
PAINT RED (-3100 -1825);
FORCEPROP 1 LAST COMMENT_BODY TRUE
R 1
J 0
(-3025 -2050);
DISPLAY 0.872340 (-3025 -2050);
PAINT PEACH (-3025 -2050);
DISPLAY INVISIBLE (-3025 -2050);
FORCEPROP 2 LAST CDS_LIB mstr_misc
J 0
(-3100 -1825);
DISPLAY INVISIBLE (-3100 -1825);
FORCEADD DNS..2
(-550 650);
PAINT RED (-550 650);
FORCEPROP 1 LAST COMMENT_BODY TRUE
R 1
J 0
(-475 425);
DISPLAY 0.872340 (-475 425);
PAINT PEACH (-475 425);
DISPLAY INVISIBLE (-475 425);
FORCEPROP 2 LAST CDS_LIB mstr_misc
J 0
(-550 650);
DISPLAY INVISIBLE (-550 650);
FORCEADD DNS..2
(-3675 550);
PAINT RED (-3675 550);
FORCEPROP 2 LAST CDS_LIB mstr_misc
J 0
(-3675 550);
DISPLAY INVISIBLE (-3675 550);
FORCEPROP 1 LAST COMMENT_BODY TRUE
R 1
J 0
(-3600 325);
DISPLAY 0.872340 (-3600 325);
PAINT PEACH (-3600 325);
DISPLAY INVISIBLE (-3600 325);
WIRE 16 -1 (-3650 -1750)(-3650 -1800);
WIRE 16 -1 (-3650 -1400)(-3650 -1475);
WIRE 16 -1 (-4025 100)(-4025 25);
WIRE 16 -1 (-3450 3350)(-3450 3400);
WIRE 16 -1 (-3450 3350)(-3800 3350);
WIRE 16 -1 (-2375 -1800)(-2375 -1700);
WIRE 16 -1 (-3000 -1800)(-2375 -1800);
WIRE 16 -1 (2725 325)(2725 400);
WIRE 16 -1 (2725 325)(2075 325);
WIRE 16 -1 (2725 325)(2725 -375);
WIRE 16 -1 (-1350 1200)(-1350 1325);
WIRE 16 -1 (-2375 -1475)(-2375 -1375);
WIRE 16 -1 (-3000 -1475)(-2375 -1475);
WIRE 16 -1 (-5225 1300)(-5225 1600);
WIRE 16 -1 (-4750 1300)(-5225 1300);
WIRE 16 -1 (-5225 1225)(-5225 1300);
WIRE 16 -1 (-525 525)(-525 475);
WIRE 16 -1 (-2950 -1050)(-2950 -950);
WIRE 16 -1 (-4025 -600)(-4025 -750);
WIRE 16 -1 (2075 -150)(2075 -200);
WIRE 16 -1 (2075 -25)(2075 -150);
WIRE 16 -1 (1825 -150)(2075 -150);
WIRE 16 -1 (-1475 -525)(-1475 -725);
WIRE 16 -1 (-1475 -475)(-1475 -525);
WIRE 16 -1 (-1625 -525)(-1475 -525);
WIRE 16 -1 (-3250 -375)(-3250 -675);
WIRE 16 -1 (-2425 -375)(-3250 -375);
WIRE 16 -1 (-3950 825)(-3950 700);
WIRE 16 -1 (-3575 825)(-3950 825);
WIRE 16 -1 (-3950 825)(-3975 825);
WIRE 16 -1 (-5225 1025)(-5225 975);
WIRE 16 -1 (-3800 2525)(-3800 2400);
WIRE 16 -1 (-3450 3150)(-3450 3100);
WIRE 16 -1 (-1625 -475)(-1475 -475);
WIRE 16 -1 (0 825)(1125 825);
FORCEPROP 2 LAST SIG_NAME PWRGD_P1V0_AUX
J 0
(390 835);
DISPLAY 0.808511 (390 835);
WIRE 16 -1 (2725 -375)(-1625 -375);
WIRE 16 -1 (2075 325)(2075 175);
WIRE 16 -1 (1825 175)(1825 325);
WIRE 16 -1 (1825 325)(2075 325);
WIRE 16 -1 (1575 175)(1575 325);
WIRE 16 -1 (1575 325)(1825 325);
WIRE 16 -1 (1325 175)(1325 325);
WIRE 16 -1 (1325 325)(1575 325);
WIRE 16 -1 (775 175)(775 325);
WIRE 16 -1 (775 325)(1325 325);
WIRE 16 -1 (375 325)(775 325);
WIRE 16 -1 (-3650 -1475)(-3200 -1475);
WIRE 16 2175 (-5375 -650)(-4250 -650);
WIRE 16 2175 (-4250 -650)(-4250 -1025);
WIRE 16 2175 (-5375 -650)(-5375 -1025);
WIRE 16 2175 (-5375 -1025)(-4250 -1025);
WIRE 16 -1 (-4775 325)(-3750 325);
FORCEPROP 0 LAST SIG_NAME EN_P1V0_AUX
J 2
(-4360 335);
DISPLAY 0.808511 (-4360 335);
WIRE 16 -1 (-4775 550)(-3750 550);
FORCEPROP 0 LAST SIG_NAME PWRGD_P1V2_AUX_R2
J 2
(-4135 560);
DISPLAY 0.808511 (-4135 560);
WIRE 16 -1 (-2425 825)(-2575 825);
WIRE 16 -1 (-2575 825)(-2575 1300);
WIRE 16 -1 (-3025 1300)(-3025 1150);
WIRE 16 -1 (-2575 1300)(-3025 1300);
WIRE 16 -1 (-3575 1150)(-3575 1300);
WIRE 16 -1 (-3575 1300)(-3025 1300);
WIRE 16 -1 (-3975 1150)(-3975 1300);
WIRE 16 -1 (-3575 1300)(-3975 1300);
WIRE 16 -1 (-4550 1300)(-3975 1300);
FORCEPROP 2 LAST SIG_NAME SW_P1V0_AUX_FLT
J 0
(-4360 1310);
DISPLAY 0.808511 (-4360 1310);
WIRE 16 -1 (-4725 2725)(-4050 2725);
FORCEPROP 0 LAST SIG_NAME PWRGD_P1V2_AUX
J 0
(-4710 2735);
DISPLAY 0.808511 (-4710 2735);
WIRE 16 -1 (-4725 2825)(-4050 2825);
FORCEPROP 0 LAST SIG_NAME PWRGD_P5V_AUX
J 0
(-4710 2835);
DISPLAY 0.808511 (-4710 2835);
WIRE 16 -1 (-2450 2775)(-3450 2775);
FORCEPROP 2 LAST SIG_NAME EN_P1V0_AUX
J 0
(-3035 2785);
DISPLAY 0.808511 (-3035 2785);
WIRE 16 -1 (-3550 550)(-3350 550);
WIRE 16 -1 (-3350 325)(-3550 325);
WIRE 16 -1 (-3350 550)(-3350 325);
WIRE 16 -1 (-2425 325)(-3350 325);
FORCEPROP 2 LAST SIG_NAME EN_P1V0_AUX_R
J 2
(-2810 335);
DISPLAY 0.808511 (-2810 335);
WIRE 16 -1 (-975 575)(-975 625);
WIRE 16 -1 (-1625 625)(-975 625);
FORCEPROP 2 LAST SIG_NAME SW_P1V0_AUX_BST
J 0
(-1535 635);
DISPLAY 0.808511 (-1535 635);
WIRE 16 -1 (-525 825)(-525 725);
WIRE 16 -1 (-525 825)(-200 825);
WIRE 16 -1 (-1350 1000)(-1350 825);
WIRE 16 -1 (-1350 825)(-525 825);
FORCEPROP 2 LAST SIG_NAME PWRGD_P1V0_AUX_R
J 0
(-1185 835);
DISPLAY 0.808511 (-1185 835);
WIRE 16 -1 (-1625 825)(-1350 825);
WIRE 16 -1 (-4025 -275)(-4025 -400);
WIRE 16 -1 (-4025 -175)(-4025 -275);
WIRE 16 -1 (-4025 -275)(-3075 -275);
FORCEPROP 2 LAST SIG_NAME P1V0_AUX_VCC
J 0
(-3610 -265);
DISPLAY 0.808511 (-3610 -265);
WIRE 16 -1 (-3075 -275)(-2425 -275);
WIRE 16 -1 (-3075 -275)(-3075 -175);
WIRE 16 -1 (-2425 -175)(-3075 -175);
WIRE 16 -1 (-3075 -175)(-3075 125);
WIRE 16 -1 (-3075 125)(-2425 125);
WIRE 16 2175 (-5375 -1425)(-4250 -1425);
WIRE 16 2175 (-4250 -1050)(-4250 -1425);
WIRE 16 2175 (-5375 -1050)(-5375 -1425);
WIRE 16 2175 (-5375 -1050)(-4250 -1050);
WIRE 16 -1 (-3975 950)(-3975 825);
WIRE 16 -1 (-3575 950)(-3575 825);
WIRE 16 -1 (-3025 825)(-3575 825);
WIRE 16 -1 (-3025 950)(-3025 825);
WIRE 16 -1 (775 -25)(775 -150);
WIRE 16 -1 (775 -150)(1325 -150);
WIRE 16 -1 (1325 -25)(1325 -150);
WIRE 16 -1 (1325 -150)(1575 -150);
WIRE 16 -1 (1575 -25)(1575 -150);
WIRE 16 -1 (1575 -150)(1825 -150);
WIRE 16 -1 (1825 -25)(1825 -150);
WIRE 16 -1 (-3650 -1800)(-3200 -1800);
WIRE 16 -1 (-3800 3025)(-3800 3350);
WIRE 16 -1 (-975 375)(-975 325);
WIRE 16 -1 (-975 325)(175 325);
WIRE 16 -1 (-1625 325)(-975 325);
FORCEPROP 2 LAST SIG_NAME SW_P1V0_AUX_SW
J 0
(-1535 335);
DISPLAY 0.808511 (-1535 335);
WIRE 16 2175 (1388 2715)(3066 2715);
WIRE 16 2175 (3066 3606)(3066 2715);
WIRE 16 2175 (1388 3606)(1388 2715);
WIRE 16 2175 (1388 3606)(3066 3606);
WIRE 16 -1 (-2950 -525)(-2950 -750);
WIRE 16 -1 (-2425 -525)(-2950 -525);
FORCEPROP 2 LAST SIG_NAME P1V0_AUX_MODE
J 0
(-2960 -515);
DISPLAY 0.808511 (-2960 -515);
DOT 1 (-1475 -525);
DOT 1 (-3025 1300);
DOT 1 (-3950 825);
DOT 1 (-3575 825);
DOT 1 (-525 825);
DOT 1 (-1350 825);
DOT 1 (-3075 -175);
DOT 1 (-3075 -275);
DOT 1 (1325 325);
DOT 1 (-975 325);
DOT 1 (-4025 -275);
DOT 1 (1325 -150);
DOT 1 (1575 -150);
DOT 1 (1575 325);
DOT 1 (1825 -150);
DOT 1 (2075 -150);
DOT 1 (1825 325);
DOT 1 (2075 325);
DOT 1 (2725 325);
DOT 1 (-3975 1300);
DOT 1 (-3575 1300);
DOT 1 (-5225 1300);
DOT 1 (-3350 325);
DOT 1 (775 325);
FORCENOTE
P1V0_AUX
(-2600 1850) 0;
DISPLAY LEFT (-2600 1850);
DISPLAY 3.148936 (-2600 1850);
FORCENOTE
IC TABLE
(-5275 -750) 0;
DISPLAY LEFT (-5275 -750);
DISPLAY 1.170213 (-5275 -750);
FORCENOTE
WORK FREQUENCY=750KHZ
(1425 2825) 0;
DISPLAY LEFT (1425 2825);
DISPLAY 0.936170 (1425 2825);
FORCENOTE
TDC=0.74A
(1425 3200) 0;
DISPLAY LEFT (1425 3200);
DISPLAY 0.936170 (1425 3200);
FORCENOTE
MAX CURRENT=0.89A
(1425 3125) 0;
DISPLAY LEFT (1425 3125);
DISPLAY 0.936170 (1425 3125);
FORCENOTE
TRANSIENT TOLERANCE=+/-5%
(1425 3275) 0;
DISPLAY LEFT (1425 3275);
DISPLAY 0.936170 (1425 3275);
FORCENOTE
OUTPUT RIPPLE=+/-1%
(1425 3350) 0;
DISPLAY LEFT (1425 3350);
DISPLAY 0.936170 (1425 3350);
FORCENOTE
OUTPUT VOLTAGE=1.0V
(1425 3425) 0;
DISPLAY LEFT (1425 3425);
DISPLAY 1.042553 (1425 3425);
FORCENOTE
DESIGN SPECIFICATION
(1425 3525) 0;
DISPLAY LEFT (1425 3525);
DISPLAY 1.170213 (1425 3525);
FORCENOTE
OVER CURRENT PROTECTION(IC RATING)=4A
(1425 3050) 0;
DISPLAY LEFT (1425 3050);
DISPLAY 0.936170 (1425 3050);
FORCENOTE
CURRENT STEP=0.89A
(1425 2975) 0;
DISPLAY LEFT (1425 2975);
DISPLAY 0.936170 (1425 2975);
FORCENOTE
SLEW RATE=0.25A/US
(1425 2900) 0;
DISPLAY LEFT (1425 2900);
DISPLAY 0.936170 (1425 2900);
FORCENOTE
1ST AL000695001
(-5275 -850) 0;
DISPLAY LEFT (-5275 -850);
DISPLAY 1.170213 (-5275 -850);
FORCENOTE
2ND AL051372000
(-5275 -950) 0;
DISPLAY LEFT (-5275 -950);
DISPLAY 1.170213 (-5275 -950);
FORCENOTE
2ND TI USE 5V
(-5275 -1350) 0;
DISPLAY LEFT (-5275 -1350);
DISPLAY 1.170213 (-5275 -1350);
FORCENOTE
1ST MPS USE 3V3
(-5275 -1250) 0;
DISPLAY LEFT (-5275 -1250);
DISPLAY 1.170213 (-5275 -1250);
FORCENOTE
R TABLE
(-5275 -1150) 0;
DISPLAY LEFT (-5275 -1150);
DISPLAY 1.170213 (-5275 -1150);
QUIT
